(kicad_pcb
	(version 20260206)
	(generator "pcbnew")
	(generator_version "10.0")
	(general
		(thickness 0.77096)
		(legacy_teardrops no)
	)
	(paper "A4")
	(layers
		(0 "F.Cu" signal "L01-Top Layer")
		(4 "In1.Cu" signal "L02-Inner Layer")
		(6 "In2.Cu" signal "L03-Inner Layer")
		(2 "B.Cu" signal "L04-Bottom Layer")
		(9 "F.Adhes" user "F.Adhesive")
		(11 "B.Adhes" user "B.Adhesive")
		(13 "F.Paste" user "Top Paste")
		(15 "B.Paste" user "Bottom Paste")
		(5 "F.SilkS" user "Top Overlay")
		(7 "B.SilkS" user "Bottom Overlay")
		(1 "F.Mask" user "Top Solder")
		(3 "B.Mask" user "Bottom Solder")
		(17 "Dwgs.User" user "User.Drawings")
		(19 "Cmts.User" user "User.Comments")
		(21 "Eco1.User" user "User.Eco1")
		(23 "Eco2.User" user "User.Eco2")
		(25 "Edge.Cuts" user)
		(27 "Margin" user)
		(31 "F.CrtYd" user "Top Courtyard")
		(29 "B.CrtYd" user "Bottom Courtyard")
		(35 "F.Fab" user "Top Component Outline")
		(33 "B.Fab" user "Bottom Component Outline 2")
	)
	(setup
		(pad_to_mask_clearance 0.05)
		(allow_soldermask_bridges_in_footprints no)
		(tenting
			(front yes)
			(back yes)
		)
		(covering
			(front no)
			(back no)
		)
		(plugging
			(front no)
			(back no)
		)
		(capping no)
		(filling no)
		(aux_axis_origin 7.100105 311.8036)
		(grid_origin 7.100105 311.8036)
		(pcbplotparams
			(layerselection 0x00000000_00000000_55555555_5755f5ff)
			(plot_on_all_layers_selection 0x00000000_00000000_00000000_00000000)
			(disableapertmacros no)
			(usegerberextensions no)
			(usegerberattributes yes)
			(usegerberadvancedattributes yes)
			(creategerberjobfile yes)
			(dashed_line_dash_ratio 12)
			(dashed_line_gap_ratio 3)
			(svgprecision 4)
			(plotframeref no)
			(mode 1)
			(useauxorigin no)
			(pdf_front_fp_property_popups yes)
			(pdf_back_fp_property_popups yes)
			(pdf_metadata yes)
			(pdf_single_document no)
			(dxfpolygonmode yes)
			(dxfimperialunits yes)
			(dxfusepcbnewfont yes)
			(psnegative no)
			(psa4output no)
			(plot_black_and_white yes)
			(sketchpadsonfab no)
			(plotpadnumbers no)
			(hidednponfab no)
			(sketchdnponfab yes)
			(crossoutdnponfab yes)
			(subtractmaskfromsilk no)
			(outputformat 1)
			(mirror no)
			(drillshape 1)
			(scaleselection 1)
			(outputdirectory "")
		)
	)
	(footprint "MyLibrary:TP1MM"
		(layer "F.Cu")
		(at 152.501105 93.3036)
		(property "Reference" "TP5"
			(at -0.522195 -1.177557 0)
			(unlocked yes)
			(layer "F.SilkS")
			(effects
				(font
					(size 0.635 0.635)
					(thickness 0.1778)
				)
			)
		)
		(property "Value" "1MM"
			(at -2.092783 1.790085 270)
			(unlocked yes)
			(layer "F.SilkS")
			(hide yes)
			(effects
				(font
					(size 0.635 0.635)
					(thickness 0.1778)
				)
			)
		)
		(sheetname "01-M2_NEO-M9N_MODULE")
		(sheetfile "01-M2_NEO-M9N_MODULE.kicad_sch")
		(duplicate_pad_numbers_are_jumpers no)
		(pad "1" smd circle
			(at 0 0)
			(size 1 1)
			(layers "F.Cu" "F.Mask" "F.Paste")
			(net "EXTIN")
			(solder_paste_margin -100)
			(thermal_bridge_angle 90)
		)
	)
	(footprint "Vault:RESC1005X40X25NL05T10"
		(layer "F.Cu")
		(at 141.701105 112.7036 90)
		(property "Reference" "R15"
			(at 0 -2.099924 90)
			(unlocked yes)
			(layer "F.SilkS")
			(effects
				(font
					(face "Arial")
					(size 0.48006 0.48006)
					(thickness 0.254)
				)
			)
		)
		(property "Value" "0_5%_0402"
			(at -2.759202 6.766925 0)
			(unlocked yes)
			(layer "F.SilkS")
			(hide yes)
			(effects
				(font
					(size 1.524 1.524)
					(thickness 0.254)
				)
			)
		)
		(sheetname "02-M2_GoldFingers")
		(sheetfile "02-M2_GoldFingers.kicad_sch")
		(duplicate_pad_numbers_are_jumpers no)
		(fp_line
			(start 0.9 -0.45)
			(end 0.9 0.45)
			(stroke
				(width 0.05)
				(type solid)
			)
			(layer "F.CrtYd")
		)
		(fp_line
			(start -0.9 -0.45)
			(end 0.9 -0.45)
			(stroke
				(width 0.05)
				(type solid)
			)
			(layer "F.CrtYd")
		)
		(fp_line
			(start -0.9 -0.45)
			(end -0.9 0.45)
			(stroke
				(width 0.05)
				(type solid)
			)
			(layer "F.CrtYd")
		)
		(fp_line
			(start 0 -0.275)
			(end 0 0.275)
			(stroke
				(width 0.1)
				(type solid)
			)
			(layer "F.CrtYd")
		)
		(fp_line
			(start -0.275 0)
			(end 0.275 0)
			(stroke
				(width 0.1)
				(type solid)
			)
			(layer "F.CrtYd")
		)
		(fp_line
			(start -0.9 0.45)
			(end 0.9 0.45)
			(stroke
				(width 0.05)
				(type solid)
			)
			(layer "F.CrtYd")
		)
		(pad "1" smd rect
			(at -0.425 0 180)
			(size 0.55 0.6)
			(layers "F.Cu" "F.Mask" "F.Paste")
			(net "NetJ1_46")
		)
		(pad "2" smd rect
			(at 0.425 0 180)
			(size 0.55 0.6)
			(layers "F.Cu" "F.Mask" "F.Paste")
			(net "TP1")
		)
	)
	(footprint "MyLibrary:c0402"
		(layer "F.Cu")
		(at 154.901105 112.4036 180)
		(property "Reference" "C3"
			(at -2.030895 -0.022443 0)
			(unlocked yes)
			(layer "F.SilkS")
			(effects
				(font
					(size 0.635 0.635)
					(thickness 0.1778)
				)
			)
		)
		(property "Value" "10nF 50V 0402"
			(at 5.065455 2.118183 180)
			(unlocked yes)
			(layer "F.SilkS")
			(hide yes)
			(effects
				(font
					(size 0.635 0.635)
					(thickness 0.1778)
				)
			)
		)
		(sheetname "01-M2_NEO-M9N_MODULE")
		(sheetfile "01-M2_NEO-M9N_MODULE.kicad_sch")
		(duplicate_pad_numbers_are_jumpers no)
		(fp_line
			(start 0.9906 0.4826)
			(end -0.9906 0.4826)
			(stroke
				(width 0.1778)
				(type solid)
			)
			(layer "F.SilkS")
		)
		(fp_line
			(start 0.9906 -0.4826)
			(end 0.9906 0.4826)
			(stroke
				(width 0.1778)
				(type solid)
			)
			(layer "F.SilkS")
		)
		(fp_line
			(start 0.9906 -0.4826)
			(end -0.9906 -0.4826)
			(stroke
				(width 0.1778)
				(type solid)
			)
			(layer "F.SilkS")
		)
		(fp_line
			(start -0.9906 -0.4826)
			(end -0.9906 0.4826)
			(stroke
				(width 0.1778)
				(type solid)
			)
			(layer "F.SilkS")
		)
		(pad "1" smd rect
			(at -0.5 0 180)
			(size 0.5 0.5)
			(layers "F.Cu" "F.Mask" "F.Paste")
			(net "GND")
		)
		(pad "2" smd rect
			(at 0.5 0 180)
			(size 0.5 0.5)
			(layers "F.Cu" "F.Mask" "F.Paste")
			(net "+3V3")
		)
	)
	(footprint "MyLibrary:r0402"
		(layer "F.Cu")
		(at 144.101105 119.1036 -90)
		(property "Reference" "R5"
			(at -1.873665 0.022443 270)
			(unlocked yes)
			(layer "F.SilkS")
			(effects
				(font
					(size 0.635 0.635)
					(thickness 0.1778)
				)
			)
		)
		(property "Value" "0 ohm 0402"
			(at 2.907155 2.168983 270)
			(unlocked yes)
			(layer "F.SilkS")
			(hide yes)
			(effects
				(font
					(size 0.635 0.635)
					(thickness 0.1778)
				)
			)
		)
		(sheetname "01-M2_NEO-M9N_MODULE")
		(sheetfile "01-M2_NEO-M9N_MODULE.kicad_sch")
		(duplicate_pad_numbers_are_jumpers no)
		(fp_line
			(start -0.9906 0.5334)
			(end -0.9906 -0.5334)
			(stroke
				(width 0.1778)
				(type solid)
			)
			(layer "F.SilkS")
		)
		(fp_line
			(start 0.9906 0.5334)
			(end -0.9906 0.5334)
			(stroke
				(width 0.1778)
				(type solid)
			)
			(layer "F.SilkS")
		)
		(fp_line
			(start 0.9906 0.5334)
			(end 0.9906 -0.5334)
			(stroke
				(width 0.1778)
				(type solid)
			)
			(layer "F.SilkS")
		)
		(fp_line
			(start 0.9906 -0.5334)
			(end -0.9906 -0.5334)
			(stroke
				(width 0.1778)
				(type solid)
			)
			(layer "F.SilkS")
		)
		(pad "1" smd rect
			(at -0.5 0 270)
			(size 0.5 0.6)
			(layers "F.Cu" "F.Mask" "F.Paste")
			(net "RX_GPS")
		)
		(pad "2" smd rect
			(at 0.5 0 270)
			(size 0.5 0.6)
			(layers "F.Cu" "F.Mask" "F.Paste")
			(net "RX_GPS_CONN")
		)
	)
	(footprint "Vault:RESC1005X40X25NL05T10"
		(layer "F.Cu")
		(at 141.301105 119.1036 -90)
		(property "Reference" "R12"
			(at -2.246 0.126931 270)
			(unlocked yes)
			(layer "F.SilkS")
			(effects
				(font
					(size 0.762 0.762)
					(thickness 0.254)
				)
			)
		)
		(property "Value" "0_5%_0402"
			(at -2.759192 6.766925 180)
			(unlocked yes)
			(layer "F.SilkS")
			(hide yes)
			(effects
				(font
					(size 1.524 1.524)
					(thickness 0.254)
				)
			)
		)
		(sheetname "02-M2_GoldFingers")
		(sheetfile "02-M2_GoldFingers.kicad_sch")
		(duplicate_pad_numbers_are_jumpers no)
		(fp_line
			(start -0.9 0.45)
			(end -0.9 -0.45)
			(stroke
				(width 0.05)
				(type solid)
			)
			(layer "F.CrtYd")
		)
		(fp_line
			(start 0.9 0.45)
			(end -0.9 0.45)
			(stroke
				(width 0.05)
				(type solid)
			)
			(layer "F.CrtYd")
		)
		(fp_line
			(start 0.9 0.45)
			(end 0.9 -0.45)
			(stroke
				(width 0.05)
				(type solid)
			)
			(layer "F.CrtYd")
		)
		(fp_line
			(start 0 0.275)
			(end 0 -0.275)
			(stroke
				(width 0.1)
				(type solid)
			)
			(layer "F.CrtYd")
		)
		(fp_line
			(start 0.275 0)
			(end -0.275 0)
			(stroke
				(width 0.1)
				(type solid)
			)
			(layer "F.CrtYd")
		)
		(fp_line
			(start 0.9 -0.45)
			(end -0.9 -0.45)
			(stroke
				(width 0.05)
				(type solid)
			)
			(layer "F.CrtYd")
		)
		(pad "1" smd rect
			(at -0.425 0)
			(size 0.55 0.6)
			(layers "F.Cu" "F.Mask" "F.Paste")
			(net "RST_GPS")
		)
		(pad "2" smd rect
			(at 0.425 0)
			(size 0.55 0.6)
			(layers "F.Cu" "F.Mask" "F.Paste")
			(net "NetJ1_67")
		)
	)
	(footprint "MyLibrary:c0402"
		(layer "F.Cu")
		(at 144.001105 90.0036 180)
		(property "Reference" "C5"
			(at -0.182795 1.077557 0)
			(unlocked yes)
			(layer "F.SilkS")
			(effects
				(font
					(size 0.635 0.635)
					(thickness 0.1778)
				)
			)
		)
		(property "Value" "10nF 50V 0402"
			(at 5.065455 2.118183 180)
			(unlocked yes)
			(layer "F.SilkS")
			(hide yes)
			(effects
				(font
					(size 0.635 0.635)
					(thickness 0.1778)
				)
			)
		)
		(sheetname "01-M2_NEO-M9N_MODULE")
		(sheetfile "01-M2_NEO-M9N_MODULE.kicad_sch")
		(duplicate_pad_numbers_are_jumpers no)
		(fp_line
			(start 0.9906 0.4826)
			(end -0.9906 0.4826)
			(stroke
				(width 0.1778)
				(type solid)
			)
			(layer "F.SilkS")
		)
		(fp_line
			(start 0.9906 -0.4826)
			(end 0.9906 0.4826)
			(stroke
				(width 0.1778)
				(type solid)
			)
			(layer "F.SilkS")
		)
		(fp_line
			(start 0.9906 -0.4826)
			(end -0.9906 -0.4826)
			(stroke
				(width 0.1778)
				(type solid)
			)
			(layer "F.SilkS")
		)
		(fp_line
			(start -0.9906 -0.4826)
			(end -0.9906 0.4826)
			(stroke
				(width 0.1778)
				(type solid)
			)
			(layer "F.SilkS")
		)
		(pad "1" smd rect
			(at -0.5 0 180)
			(size 0.5 0.5)
			(layers "F.Cu" "F.Mask" "F.Paste")
			(net "GND")
		)
		(pad "2" smd rect
			(at 0.5 0 180)
			(size 0.5 0.5)
			(layers "F.Cu" "F.Mask" "F.Paste")
			(net "NetC5_2")
		)
	)
	(footprint "Vault:FP-GRM31C-0_2-e0_3_0_8-IPC_C"
		(layer "F.Cu")
		(at 154.801105 114.1036)
		(property "Reference" "C6"
			(at -2.646005 0.126931 0)
			(unlocked yes)
			(layer "F.SilkS")
			(effects
				(font
					(size 0.762 0.762)
					(thickness 0.254)
				)
			)
		)
		(property "Value" "47uF_6.3V_1206"
			(at 8.620015 2.683002 0)
			(unlocked yes)
			(layer "F.SilkS")
			(hide yes)
			(effects
				(font
					(size 1.524 1.524)
					(thickness 0.254)
				)
			)
		)
		(sheetname "02-M2_GoldFingers")
		(sheetfile "02-M2_GoldFingers.kicad_sch")
		(duplicate_pad_numbers_are_jumpers no)
		(fp_line
			(start -0.39846 -0.9)
			(end 0.39847 -0.9)
			(stroke
				(width 0.2)
				(type solid)
			)
			(layer "F.SilkS")
		)
		(fp_line
			(start -0.39846 0.9)
			(end 0.39847 0.9)
			(stroke
				(width 0.2)
				(type solid)
			)
			(layer "F.SilkS")
		)
		(fp_line
			(start -1.9531 -1)
			(end 1.9531 -1)
			(stroke
				(width 0.2)
				(type solid)
			)
			(layer "F.CrtYd")
		)
		(fp_line
			(start -1.9531 1)
			(end -1.9531 -1)
			(stroke
				(width 0.2)
				(type solid)
			)
			(layer "F.CrtYd")
		)
		(fp_line
			(start -1.9531 1)
			(end 1.9531 1)
			(stroke
				(width 0.2)
				(type solid)
			)
			(layer "F.CrtYd")
		)
		(fp_line
			(start 1.9531 1)
			(end 1.9531 -1)
			(stroke
				(width 0.2)
				(type solid)
			)
			(layer "F.CrtYd")
		)
		(fp_line
			(start -1.9531 -1)
			(end 1.9531 -1)
			(stroke
				(width 0.2)
				(type solid)
			)
			(layer "F.Fab")
		)
		(fp_line
			(start -1.9531 1)
			(end -1.9531 -1)
			(stroke
				(width 0.2)
				(type solid)
			)
			(layer "F.Fab")
		)
		(fp_line
			(start -1.9531 1)
			(end 1.9531 1)
			(stroke
				(width 0.2)
				(type solid)
			)
			(layer "F.Fab")
		)
		(fp_line
			(start -0.5 0)
			(end 0.5 0)
			(stroke
				(width 0.1)
				(type solid)
			)
			(layer "F.Fab")
		)
		(fp_line
			(start 0 0.5)
			(end 0 -0.5)
			(stroke
				(width 0.1)
				(type solid)
			)
			(layer "F.Fab")
		)
		(fp_line
			(start 1.9531 1)
			(end 1.9531 -1)
			(stroke
				(width 0.2)
				(type solid)
			)
			(layer "F.Fab")
		)
		(fp_text user "${REFERENCE}"
			(at -0.00001 0.09602 0)
			(unlocked yes)
			(layer "F.Fab")
			(effects
				(font
					(face "Arial")
					(size 0.63 0.63)
					(thickness 0.1)
				)
				(justify left bottom)
			)
		)
		(pad "1" smd rect
			(at -1.27578 0)
			(size 1.15464 1.7062)
			(layers "F.Cu" "F.Mask" "F.Paste")
			(net "+3V3")
			(solder_mask_margin 0)
			(solder_paste_margin 0)
		)
		(pad "2" smd rect
			(at 1.27578 0)
			(size 1.15464 1.7062)
			(layers "F.Cu" "F.Mask" "F.Paste")
			(net "GND")
			(solder_mask_margin 0)
			(solder_paste_margin 0)
		)
	)
	(footprint "MyLibrary:c0402"
		(layer "F.Cu")
		(at 154.901105 110.0036 180)
		(property "Reference" "C1"
			(at -1.977795 -0.022443 0)
			(unlocked yes)
			(layer "F.SilkS")
			(effects
				(font
					(size 0.635 0.635)
					(thickness 0.1778)
				)
			)
		)
		(property "Value" "1uF 6V3 0402"
			(at 4.3037 2.118183 180)
			(unlocked yes)
			(layer "F.SilkS")
			(hide yes)
			(effects
				(font
					(size 0.635 0.635)
					(thickness 0.1778)
				)
			)
		)
		(sheetname "01-M2_NEO-M9N_MODULE")
		(sheetfile "01-M2_NEO-M9N_MODULE.kicad_sch")
		(duplicate_pad_numbers_are_jumpers no)
		(fp_line
			(start 0.9906 0.4826)
			(end -0.9906 0.4826)
			(stroke
				(width 0.1778)
				(type solid)
			)
			(layer "F.SilkS")
		)
		(fp_line
			(start 0.9906 -0.4826)
			(end 0.9906 0.4826)
			(stroke
				(width 0.1778)
				(type solid)
			)
			(layer "F.SilkS")
		)
		(fp_line
			(start 0.9906 -0.4826)
			(end -0.9906 -0.4826)
			(stroke
				(width 0.1778)
				(type solid)
			)
			(layer "F.SilkS")
		)
		(fp_line
			(start -0.9906 -0.4826)
			(end -0.9906 0.4826)
			(stroke
				(width 0.1778)
				(type solid)
			)
			(layer "F.SilkS")
		)
		(pad "1" smd rect
			(at -0.5 0 180)
			(size 0.5 0.5)
			(layers "F.Cu" "F.Mask" "F.Paste")
			(net "GND")
		)
		(pad "2" smd rect
			(at 0.5 0 180)
			(size 0.5 0.5)
			(layers "F.Cu" "F.Mask" "F.Paste")
			(net "+3V3")
		)
	)
	(footprint "MyLibrary:TP1MM"
		(layer "F.Cu")
		(at 155.201105 93.7036)
		(property "Reference" "TP1"
			(at 1.677805 0.292633 0)
			(unlocked yes)
			(layer "F.SilkS")
			(effects
				(font
					(size 0.635 0.635)
					(thickness 0.1778)
				)
			)
		)
		(property "Value" "1MM"
			(at -2.092783 1.790085 270)
			(unlocked yes)
			(layer "F.SilkS")
			(hide yes)
			(effects
				(font
					(size 0.635 0.635)
					(thickness 0.1778)
				)
			)
		)
		(sheetname "01-M2_NEO-M9N_MODULE")
		(sheetfile "01-M2_NEO-M9N_MODULE.kicad_sch")
		(duplicate_pad_numbers_are_jumpers no)
		(pad "1" smd circle
			(at 0 0)
			(size 1 1)
			(layers "F.Cu" "F.Mask" "F.Paste")
			(net "D_SEL")
			(solder_paste_margin -100)
			(thermal_bridge_angle 90)
		)
	)
	(footprint "MyLibrary:r0402"
		(layer "F.Cu")
		(at 154.001105 90.0036 180)
		(property "Reference" "R7"
			(at 0.622005 2.177557 0)
			(unlocked yes)
			(layer "F.SilkS")
			(effects
				(font
					(size 0.635 0.635)
					(thickness 0.178)
				)
			)
		)
		(property "Value" "0 ohm 0402"
			(at 6.79212 2.200402 180)
			(unlocked yes)
			(layer "F.SilkS")
			(hide yes)
			(effects
				(font
					(size 1.524 1.524)
					(thickness 0.254)
				)
			)
		)
		(sheetname "01-M2_NEO-M9N_MODULE")
		(sheetfile "01-M2_NEO-M9N_MODULE.kicad_sch")
		(duplicate_pad_numbers_are_jumpers no)
		(fp_line
			(start 0.9906 0.5334)
			(end -0.9906 0.5334)
			(stroke
				(width 0.1778)
				(type solid)
			)
			(layer "F.SilkS")
		)
		(fp_line
			(start 0.9906 -0.5334)
			(end 0.9906 0.5334)
			(stroke
				(width 0.1778)
				(type solid)
			)
			(layer "F.SilkS")
		)
		(fp_line
			(start 0.9906 -0.5334)
			(end -0.9906 -0.5334)
			(stroke
				(width 0.1778)
				(type solid)
			)
			(layer "F.SilkS")
		)
		(fp_line
			(start -0.9906 -0.5334)
			(end -0.9906 0.5334)
			(stroke
				(width 0.1778)
				(type solid)
			)
			(layer "F.SilkS")
		)
		(pad "1" smd rect
			(at -0.5 0 180)
			(size 0.5 0.6)
			(layers "F.Cu" "F.Mask" "F.Paste")
			(net "LNA_EN")
		)
		(pad "2" smd rect
			(at 0.5 0 180)
			(size 0.5 0.6)
			(layers "F.Cu" "F.Mask" "F.Paste")
			(net "NetQ1_1")
		)
	)
	(footprint "Vault:FP-U_FL-R-SMT-1_10-MFG"
		(layer "F.Cu")
		(at 140.901105 86.1036 180)
		(property "Reference" "J2"
			(at -3.064092 -0.477805 270)
			(unlocked yes)
			(layer "F.SilkS")
			(effects
				(font
					(size 1.016 1.016)
					(thickness 0.1778)
				)
			)
		)
		(property "Value" "U.FL-R-SMT-1(10)"
			(at 7.55289 12.938543 180)
			(unlocked yes)
			(layer "F.SilkS")
			(hide yes)
			(effects
				(font
					(size 0.635 0.635)
					(thickness 0.1778)
				)
			)
		)
		(sheetname "01-M2_NEO-M9N_MODULE")
		(sheetfile "01-M2_NEO-M9N_MODULE.kicad_sch")
		(duplicate_pad_numbers_are_jumpers no)
		(fp_line
			(start 0.575 1.375)
			(end -0.575 1.375)
			(stroke
				(width 0.2)
				(type solid)
			)
			(layer "F.SilkS")
		)
		(fp_rect
			(start 1.0499 1.00009)
			(end 1.9499 -0.99991)
			(stroke
				(width 0)
				(type default)
			)
			(fill yes)
			(layer "F.Paste")
		)
		(fp_rect
			(start -0.4 -1.09888)
			(end 0.39999 -1.94888)
			(stroke
				(width 0)
				(type default)
			)
			(fill yes)
			(layer "F.Paste")
		)
		(fp_rect
			(start -1.94989 0.99991)
			(end -1.04989 -1.00009)
			(stroke
				(width 0)
				(type default)
			)
			(fill yes)
			(layer "F.Paste")
		)
		(fp_line
			(start 2.1 1.475)
			(end -2.1 1.475)
			(stroke
				(width 0.2)
				(type solid)
			)
			(layer "F.CrtYd")
		)
		(fp_line
			(start 2.1 -2.15)
			(end 2.1 1.475)
			(stroke
				(width 0.2)
				(type solid)
			)
			(layer "F.CrtYd")
		)
		(fp_line
			(start 2.1 -2.15)
			(end -2.1 -2.15)
			(stroke
				(width 0.2)
				(type solid)
			)
			(layer "F.CrtYd")
		)
		(fp_line
			(start -2.1 -2.15)
			(end -2.1 1.475)
			(stroke
				(width 0.2)
				(type solid)
			)
			(layer "F.CrtYd")
		)
		(fp_line
			(start 2.1 1.475)
			(end -2.1 1.475)
			(stroke
				(width 0.2)
				(type solid)
			)
			(layer "F.Fab")
		)
		(fp_line
			(start 2.1 -2.15)
			(end 2.1 1.475)
			(stroke
				(width 0.2)
				(type solid)
			)
			(layer "F.Fab")
		)
		(fp_line
			(start 2.1 -2.15)
			(end -2.1 -2.15)
			(stroke
				(width 0.2)
				(type solid)
			)
			(layer "F.Fab")
		)
		(fp_line
			(start 0.54375 0)
			(end -0.54375 0)
			(stroke
				(width 0.1)
				(type solid)
			)
			(layer "F.Fab")
		)
		(fp_line
			(start 0 -0.54375)
			(end 0 0.54375)
			(stroke
				(width 0.1)
				(type solid)
			)
			(layer "F.Fab")
		)
		(fp_line
			(start -2.1 -2.15)
			(end -2.1 1.475)
			(stroke
				(width 0.2)
				(type solid)
			)
			(layer "F.Fab")
		)
		(fp_text user "${REFERENCE}"
			(at -0.00186 -0.24148 180)
			(unlocked yes)
			(layer "F.Fab")
			(effects
				(font
					(face "Arial")
					(size 0.63 0.63)
					(thickness 0.1)
				)
				(justify left bottom)
			)
		)
		(pad "1" smd rect
			(at 0 -1.525 180)
			(size 1 1.05)
			(layers "F.Cu" "F.Mask" "F.Paste")
			(net "RF_ANT")
			(solder_mask_margin 0)
			(solder_paste_margin -1000)
		)
		(pad "2" smd rect
			(at -1.475 0 180)
			(size 1.05 2.2)
			(layers "F.Cu" "F.Mask" "F.Paste")
			(net "GND")
			(solder_mask_margin 0)
			(solder_paste_margin -1000)
		)
		(pad "3" smd rect
			(at 1.475 0 180)
			(size 1.05 2.2)
			(layers "F.Cu" "F.Mask" "F.Paste")
			(net "GND")
			(solder_mask_margin 0)
			(solder_paste_margin -1000)
		)
	)
	(footprint "MyLibrary:TP1MM"
		(layer "F.Cu")
		(at 154.501105 88.5036)
		(property "Reference" "TP6"
			(at 1.112805 -1.077557 0)
			(unlocked yes)
			(layer "F.SilkS")
			(effects
				(font
					(size 0.635 0.635)
					(thickness 0.1778)
				)
			)
		)
		(property "Value" "1MM"
			(at -2.092793 1.790085 270)
			(unlocked yes)
			(layer "F.SilkS")
			(hide yes)
			(effects
				(font
					(size 0.635 0.635)
					(thickness 0.1778)
				)
			)
		)
		(sheetname "01-M2_NEO-M9N_MODULE")
		(sheetfile "01-M2_NEO-M9N_MODULE.kicad_sch")
		(duplicate_pad_numbers_are_jumpers no)
		(pad "1" smd circle
			(at 0 0)
			(size 1 1)
			(layers "F.Cu" "F.Mask" "F.Paste")
			(net "LNA_EN")
			(solder_paste_margin -100)
			(thermal_bridge_angle 90)
		)
	)
	(footprint "MyLibrary:c0402"
		(layer "F.Cu")
		(at 141.401105 91.7036 -90)
		(property "Reference" "C4"
			(at -0.128635 1.182557 90)
			(unlocked yes)
			(layer "F.SilkS")
			(effects
				(font
					(size 0.635 0.635)
					(thickness 0.1778)
				)
			)
		)
		(property "Value" "47pF 50V 0402"
			(at 5.192415 2.266303 270)
			(unlocked yes)
			(layer "F.SilkS")
			(hide yes)
			(effects
				(font
					(size 0.635 0.635)
					(thickness 0.1778)
				)
			)
		)
		(sheetname "01-M2_NEO-M9N_MODULE")
		(sheetfile "01-M2_NEO-M9N_MODULE.kicad_sch")
		(duplicate_pad_numbers_are_jumpers no)
		(fp_line
			(start -0.9906 0.4826)
			(end -0.9906 -0.4826)
			(stroke
				(width 0.1778)
				(type solid)
			)
			(layer "F.SilkS")
		)
		(fp_line
			(start 0.9906 0.4826)
			(end -0.9906 0.4826)
			(stroke
				(width 0.1778)
				(type solid)
			)
			(layer "F.SilkS")
		)
		(fp_line
			(start 0.9906 0.4826)
			(end 0.9906 -0.4826)
			(stroke
				(width 0.1778)
				(type solid)
			)
			(layer "F.SilkS")
		)
		(fp_line
			(start 0.9906 -0.4826)
			(end -0.9906 -0.4826)
			(stroke
				(width 0.1778)
				(type solid)
			)
			(layer "F.SilkS")
		)
		(pad "1" smd rect
			(at -0.5 0 270)
			(size 0.5 0.5)
			(layers "F.Cu" "F.Mask" "F.Paste")
			(net "RF_ANT")
		)
		(pad "2" smd rect
			(at 0.5 0 270)
			(size 0.5 0.5)
			(layers "F.Cu" "F.Mask" "F.Paste")
			(net "RF_MODULE")
		)
	)
	(footprint "MyLibrary:r0402"
		(layer "F.Cu")
		(at 154.001105 92.0036)
		(property "Reference" "R9"
			(at -0.622005 -3.177557 0)
			(unlocked yes)
			(layer "F.SilkS")
			(effects
				(font
					(size 0.635 0.635)
					(thickness 0.178)
				)
			)
		)
		(property "Value" "DNI 0 ohm 0402"
			(at 6.792115 2.200402 0)
			(unlocked yes)
			(layer "F.SilkS")
			(hide yes)
			(effects
				(font
					(size 1.524 1.524)
					(thickness 0.254)
				)
			)
		)
		(sheetname "01-M2_NEO-M9N_MODULE")
		(sheetfile "01-M2_NEO-M9N_MODULE.kicad_sch")
		(duplicate_pad_numbers_are_jumpers no)
		(fp_line
			(start -0.9906 -0.5334)
			(end 0.9906 -0.5334)
			(stroke
				(width 0.1778)
				(type solid)
			)
			(layer "F.SilkS")
		)
		(fp_line
			(start -0.9906 0.5334)
			(end -0.9906 -0.5334)
			(stroke
				(width 0.1778)
				(type solid)
			)
			(layer "F.SilkS")
		)
		(fp_line
			(start -0.9906 0.5334)
			(end 0.9906 0.5334)
			(stroke
				(width 0.1778)
				(type solid)
			)
			(layer "F.SilkS")
		)
		(fp_line
			(start 0.9906 0.5334)
			(end 0.9906 -0.5334)
			(stroke
				(width 0.1778)
				(type solid)
			)
			(layer "F.SilkS")
		)
		(pad "1" smd rect
			(at -0.5 0)
			(size 0.5 0.6)
			(layers "F.Cu" "F.Mask" "F.Paste")
			(net "NetQ1_1")
		)
		(pad "2" smd rect
			(at 0.5 0)
			(size 0.5 0.6)
			(layers "F.Cu" "F.Mask" "F.Paste")
			(net "GND")
		)
	)
	(footprint "Vault:RESC1005X40X25NL05T10"
		(layer "F.Cu")
		(at 140.601105 112.7036 90)
		(property "Reference" "R14"
			(at -0.000005 -1.795704 90)
			(unlocked yes)
			(layer "F.SilkS")
			(effects
				(font
					(face "Arial")
					(size 0.48006 0.48006)
					(thickness 0.254)
				)
			)
		)
		(property "Value" "DNI_0_5%_0402"
			(at -2.759202 9.68698 0)
			(unlocked yes)
			(layer "F.SilkS")
			(hide yes)
			(effects
				(font
					(size 1.524 1.524)
					(thickness 0.254)
				)
			)
		)
		(sheetname "02-M2_GoldFingers")
		(sheetfile "02-M2_GoldFingers.kicad_sch")
		(duplicate_pad_numbers_are_jumpers no)
		(fp_line
			(start 0.9 -0.45)
			(end 0.9 0.45)
			(stroke
				(width 0.05)
				(type solid)
			)
			(layer "F.CrtYd")
		)
		(fp_line
			(start -0.9 -0.45)
			(end 0.9 -0.45)
			(stroke
				(width 0.05)
				(type solid)
			)
			(layer "F.CrtYd")
		)
		(fp_line
			(start -0.9 -0.45)
			(end -0.9 0.45)
			(stroke
				(width 0.05)
				(type solid)
			)
			(layer "F.CrtYd")
		)
		(fp_line
			(start 0 -0.275)
			(end 0 0.275)
			(stroke
				(width 0.1)
				(type solid)
			)
			(layer "F.CrtYd")
		)
		(fp_line
			(start -0.275 0)
			(end 0.275 0)
			(stroke
				(width 0.1)
				(type solid)
			)
			(layer "F.CrtYd")
		)
		(fp_line
			(start -0.9 0.45)
			(end 0.9 0.45)
			(stroke
				(width 0.05)
				(type solid)
			)
			(layer "F.CrtYd")
		)
		(pad "1" smd rect
			(at -0.425 0 180)
			(size 0.55 0.6)
			(layers "F.Cu" "F.Mask" "F.Paste")
			(net "NetJ1_35")
		)
		(pad "2" smd rect
			(at 0.425 0 180)
			(size 0.55 0.6)
			(layers "F.Cu" "F.Mask" "F.Paste")
			(net "TP1")
		)
	)
	(footprint "MyLibrary:TP1MM"
		(layer "F.Cu")
		(at 157.601105 95.9036)
		(property "Reference" "TP7"
			(at 0.277805 1.322443 0)
			(unlocked yes)
			(layer "F.SilkS")
			(effects
				(font
					(size 0.635 0.635)
					(thickness 0.1778)
				)
			)
		)
		(property "Value" "1MM"
			(at -2.092783 1.790085 270)
			(unlocked yes)
			(layer "F.SilkS")
			(hide yes)
			(effects
				(font
					(size 0.635 0.635)
					(thickness 0.1778)
				)
			)
		)
		(sheetname "01-M2_NEO-M9N_MODULE")
		(sheetfile "01-M2_NEO-M9N_MODULE.kicad_sch")
		(duplicate_pad_numbers_are_jumpers no)
		(pad "1" smd circle
			(at 0 0)
			(size 1 1)
			(layers "F.Cu" "F.Mask" "F.Paste")
			(net "SAFEBOOT_N")
			(solder_paste_margin -100)
			(thermal_bridge_angle 90)
		)
	)
	(footprint "Vault:FP-GRM31C-0_2-e0_3_0_8-IPC_C"
		(layer "F.Cu")
		(at 154.801105 116.4036)
		(property "Reference" "C7"
			(at -2.546005 0.026921 0)
			(unlocked yes)
			(layer "F.SilkS")
			(effects
				(font
					(size 0.762 0.762)
					(thickness 0.254)
				)
			)
		)
		(property "Value" "47uF_6.3V_1206"
			(at 8.620015 2.683002 0)
			(unlocked yes)
			(layer "F.SilkS")
			(hide yes)
			(effects
				(font
					(size 1.524 1.524)
					(thickness 0.254)
				)
			)
		)
		(sheetname "02-M2_GoldFingers")
		(sheetfile "02-M2_GoldFingers.kicad_sch")
		(duplicate_pad_numbers_are_jumpers no)
		(fp_line
			(start -0.39846 -0.9)
			(end 0.39847 -0.9)
			(stroke
				(width 0.2)
				(type solid)
			)
			(layer "F.SilkS")
		)
		(fp_line
			(start -0.39846 0.9)
			(end 0.39847 0.9)
			(stroke
				(width 0.2)
				(type solid)
			)
			(layer "F.SilkS")
		)
		(fp_line
			(start -1.9531 -1)
			(end 1.9531 -1)
			(stroke
				(width 0.2)
				(type solid)
			)
			(layer "F.CrtYd")
		)
		(fp_line
			(start -1.9531 1)
			(end -1.9531 -1)
			(stroke
				(width 0.2)
				(type solid)
			)
			(layer "F.CrtYd")
		)
		(fp_line
			(start -1.9531 1)
			(end 1.9531 1)
			(stroke
				(width 0.2)
				(type solid)
			)
			(layer "F.CrtYd")
		)
		(fp_line
			(start 1.9531 1)
			(end 1.9531 -1)
			(stroke
				(width 0.2)
				(type solid)
			)
			(layer "F.CrtYd")
		)
		(fp_line
			(start -1.9531 -1)
			(end 1.9531 -1)
			(stroke
				(width 0.2)
				(type solid)
			)
			(layer "F.Fab")
		)
		(fp_line
			(start -1.9531 1)
			(end -1.9531 -1)
			(stroke
				(width 0.2)
				(type solid)
			)
			(layer "F.Fab")
		)
		(fp_line
			(start -1.9531 1)
			(end 1.9531 1)
			(stroke
				(width 0.2)
				(type solid)
			)
			(layer "F.Fab")
		)
		(fp_line
			(start -0.5 0)
			(end 0.5 0)
			(stroke
				(width 0.1)
				(type solid)
			)
			(layer "F.Fab")
		)
		(fp_line
			(start 0 0.5)
			(end 0 -0.5)
			(stroke
				(width 0.1)
				(type solid)
			)
			(layer "F.Fab")
		)
		(fp_line
			(start 1.9531 1)
			(end 1.9531 -1)
			(stroke
				(width 0.2)
				(type solid)
			)
			(layer "F.Fab")
		)
		(fp_text user "${REFERENCE}"
			(at -0.00001 0.09602 0)
			(unlocked yes)
			(layer "F.Fab")
			(effects
				(font
					(face "Arial")
					(size 0.63 0.63)
					(thickness 0.1)
				)
				(justify left bottom)
			)
		)
		(pad "1" smd rect
			(at -1.27578 0)
			(size 1.15464 1.7062)
			(layers "F.Cu" "F.Mask" "F.Paste")
			(net "+3V3")
			(solder_mask_margin 0)
			(solder_paste_margin 0)
		)
		(pad "2" smd rect
			(at 1.27578 0)
			(size 1.15464 1.7062)
			(layers "F.Cu" "F.Mask" "F.Paste")
			(net "GND")
			(solder_mask_margin 0)
			(solder_paste_margin 0)
		)
	)
	(footprint "MyLibrary:led0603"
		(layer "F.Cu")
		(at 146.039455 111.39962 90)
		(property "Reference" "LED1"
			(at 1.473577 -1.79363 360)
			(unlocked yes)
			(layer "F.SilkS")
			(effects
				(font
					(size 0.635 0.635)
					(thickness 0.1778)
				)
			)
		)
		(property "Value" "Green"
			(at -3.032593 3.262755 0)
			(unlocked yes)
			(layer "F.SilkS")
			(hide yes)
			(effects
				(font
					(size 0.635 0.635)
					(thickness 0.1778)
				)
			)
		)
		(sheetname "01-M2_NEO-M9N_MODULE")
		(sheetfile "01-M2_NEO-M9N_MODULE.kicad_sch")
		(duplicate_pad_numbers_are_jumpers no)
		(fp_line
			(start 1.397 -0.635)
			(end 1.397 0.635)
			(stroke
				(width 0.1778)
				(type solid)
			)
			(layer "F.SilkS")
		)
		(fp_line
			(start -1.397 -0.635)
			(end 1.397 -0.635)
			(stroke
				(width 0.1778)
				(type solid)
			)
			(layer "F.SilkS")
		)
		(fp_line
			(start -1.397 -0.635)
			(end -1.397 0.635)
			(stroke
				(width 0.1778)
				(type solid)
			)
			(layer "F.SilkS")
		)
		(fp_line
			(start -0.03175 -0.12065)
			(end 0.08255 -0.00635)
			(stroke
				(width 0.0762)
				(type solid)
			)
			(layer "F.SilkS")
		)
		(fp_line
			(start -0.03175 -0.12065)
			(end -0.03175 0.10795)
			(stroke
				(width 0.0762)
				(type solid)
			)
			(layer "F.SilkS")
		)
		(fp_line
			(start 0.08255 -0.00635)
			(end -0.03175 0.10795)
			(stroke
				(width 0.0762)
				(type solid)
			)
			(layer "F.SilkS")
		)
		(fp_line
			(start -1.397 0.635)
			(end 1.397 0.635)
			(stroke
				(width 0.1778)
				(type solid)
			)
			(layer "F.SilkS")
		)
		(fp_rect
			(start -0.03203 0.04853)
			(end 0.03706 -0.05242)
			(stroke
				(width 0)
				(type default)
			)
			(fill yes)
			(layer "F.SilkS")
		)
		(pad "1" smd rect
			(at -0.75 0 90)
			(size 0.8 0.8)
			(layers "F.Cu" "F.Mask" "F.Paste")
			(net "NetLED1_1")
		)
		(pad "2" smd rect
			(at 0.75 0 90)
			(size 0.8 0.8)
			(layers "F.Cu" "F.Mask" "F.Paste")
			(net "NetLED1_2")
		)
	)
	(footprint "Vault:RESC1005X40X25NL05T05"
		(layer "F.Cu")
		(at 149.501105 115.4036)
		(property "Reference" "R3"
			(at -1.322205 0.522443 0)
			(unlocked yes)
			(layer "F.SilkS")
			(effects
				(font
					(size 0.635 0.635)
					(thickness 0.1778)
				)
			)
		)
		(property "Value" "1K_1%_0402"
			(at 4.938495 2.168983 0)
			(unlocked yes)
			(layer "F.SilkS")
			(hide yes)
			(effects
				(font
					(size 0.635 0.635)
					(thickness 0.1778)
				)
			)
		)
		(sheetname "01-M2_NEO-M9N_MODULE")
		(sheetfile "01-M2_NEO-M9N_MODULE.kicad_sch")
		(duplicate_pad_numbers_are_jumpers no)
		(fp_line
			(start -0.9 -0.45)
			(end 0.9 -0.45)
			(stroke
				(width 0.05)
				(type solid)
			)
			(layer "F.CrtYd")
		)
		(fp_line
			(start -0.9 0.45)
			(end -0.9 -0.45)
			(stroke
				(width 0.05)
				(type solid)
			)
			(layer "F.CrtYd")
		)
		(fp_line
			(start -0.9 0.45)
			(end 0.9 0.45)
			(stroke
				(width 0.05)
				(type solid)
			)
			(layer "F.CrtYd")
		)
		(fp_line
			(start -0.275 0)
			(end 0.275 0)
			(stroke
				(width 0.1)
				(type solid)
			)
			(layer "F.CrtYd")
		)
		(fp_line
			(start 0 0.275)
			(end 0 -0.275)
			(stroke
				(width 0.1)
				(type solid)
			)
			(layer "F.CrtYd")
		)
		(fp_line
			(start 0.9 0.45)
			(end 0.9 -0.45)
			(stroke
				(width 0.05)
				(type solid)
			)
			(layer "F.CrtYd")
		)
		(pad "1" smd rect
			(at -0.45 0 90)
			(size 0.55 0.55)
			(layers "F.Cu" "F.Mask" "F.Paste")
			(net "GND")
		)
		(pad "2" smd rect
			(at 0.45 0 90)
			(size 0.55 0.55)
			(layers "F.Cu" "F.Mask" "F.Paste")
			(net "NetLED2_2")
		)
	)
	(footprint "MyLibrary:r0402"
		(layer "F.Cu")
		(at 151.601105 90.4036 90)
		(property "Reference" "R6"
			(at 2.178005 -0.077567 90)
			(unlocked yes)
			(layer "F.SilkS")
			(effects
				(font
					(size 0.635 0.635)
					(thickness 0.178)
				)
			)
		)
		(property "Value" "DNI 0 ohm 0402"
			(at 6.792115 2.200402 90)
			(unlocked yes)
			(layer "F.SilkS")
			(hide yes)
			(effects
				(font
					(size 1.524 1.524)
					(thickness 0.254)
				)
			)
		)
		(sheetname "01-M2_NEO-M9N_MODULE")
		(sheetfile "01-M2_NEO-M9N_MODULE.kicad_sch")
		(duplicate_pad_numbers_are_jumpers no)
		(fp_line
			(start 0.9906 -0.5334)
			(end 0.9906 0.5334)
			(stroke
				(width 0.1778)
				(type solid)
			)
			(layer "F.SilkS")
		)
		(fp_line
			(start -0.9906 -0.5334)
			(end 0.9906 -0.5334)
			(stroke
				(width 0.1778)
				(type solid)
			)
			(layer "F.SilkS")
		)
		(fp_line
			(start -0.9906 -0.5334)
			(end -0.9906 0.5334)
			(stroke
				(width 0.1778)
				(type solid)
			)
			(layer "F.SilkS")
		)
		(fp_line
			(start -0.9906 0.5334)
			(end 0.9906 0.5334)
			(stroke
				(width 0.1778)
				(type solid)
			)
			(layer "F.SilkS")
		)
		(pad "1" smd rect
			(at -0.5 0 90)
			(size 0.5 0.6)
			(layers "F.Cu" "F.Mask" "F.Paste")
			(net "NetQ1_1")
		)
		(pad "2" smd rect
			(at 0.5 0 90)
			(size 0.5 0.6)
			(layers "F.Cu" "F.Mask" "F.Paste")
			(net "+3V3")
		)
	)
	(footprint "MyLibrary:TP1MM"
		(layer "F.Cu")
		(at 152.001105 110.6036 90)
		(property "Reference" "TP10"
			(at -0.5728 1.110207 270)
			(unlocked yes)
			(layer "F.SilkS")
			(effects
				(font
					(size 0.635 0.635)
					(thickness 0.1778)
				)
			)
		)
		(property "Value" "1MM"
			(at -2.092783 1.790085 0)
			(unlocked yes)
			(layer "F.SilkS")
			(hide yes)
			(effects
				(font
					(size 0.635 0.635)
					(thickness 0.1778)
				)
			)
		)
		(sheetname "01-M2_NEO-M9N_MODULE")
		(sheetfile "01-M2_NEO-M9N_MODULE.kicad_sch")
		(duplicate_pad_numbers_are_jumpers no)
		(pad "1" smd circle
			(at 0 0 90)
			(size 1 1)
			(layers "F.Cu" "F.Mask" "F.Paste")
			(net "RX_GPS")
			(solder_paste_margin -100)
			(thermal_bridge_angle 90)
		)
	)
	(footprint "Vault:RESC1005X40X25LL05T10"
		(layer "F.Cu")
		(at 149.201105 112.7036 -90)
		(property "Reference" "R2"
			(at 0.645995 -1.126921 90)
			(unlocked yes)
			(layer "F.SilkS")
			(effects
				(font
					(size 0.762 0.762)
					(thickness 0.254)
				)
			)
		)
		(property "Value" "10K_5%_0402"
			(at 7.858675 2.251202 270)
			(unlocked yes)
			(layer "F.SilkS")
			(hide yes)
			(effects
				(font
					(size 1.524 1.524)
					(thickness 0.254)
				)
			)
		)
		(sheetname "01-M2_NEO-M9N_MODULE")
		(sheetfile "01-M2_NEO-M9N_MODULE.kicad_sch")
		(duplicate_pad_numbers_are_jumpers no)
		(fp_line
			(start -0.75 0.4)
			(end -0.75 -0.4)
			(stroke
				(width 0.05)
				(type solid)
			)
			(layer "F.CrtYd")
		)
		(fp_line
			(start 0.75 0.4)
			(end -0.75 0.4)
			(stroke
				(width 0.05)
				(type solid)
			)
			(layer "F.CrtYd")
		)
		(fp_line
			(start 0.75 0.4)
			(end 0.75 -0.4)
			(stroke
				(width 0.05)
				(type solid)
			)
			(layer "F.CrtYd")
		)
		(fp_line
			(start 0 0.275)
			(end 0 -0.275)
			(stroke
				(width 0.1)
				(type solid)
			)
			(layer "F.CrtYd")
		)
		(fp_line
			(start 0.275 0)
			(end -0.275 0)
			(stroke
				(width 0.1)
				(type solid)
			)
			(layer "F.CrtYd")
		)
		(fp_line
			(start 0.75 -0.4)
			(end -0.75 -0.4)
			(stroke
				(width 0.05)
				(type solid)
			)
			(layer "F.CrtYd")
		)
		(pad "1" smd rect
			(at -0.375 0)
			(size 0.45 0.5)
			(layers "F.Cu" "F.Mask" "F.Paste")
			(net "SCL")
		)
		(pad "2" smd rect
			(at 0.375 0)
			(size 0.45 0.5)
			(layers "F.Cu" "F.Mask" "F.Paste")
			(net "+3V3")
		)
	)
	(footprint "MyLibrary:IC_NEO-M9N"
		(layer "F.Cu")
		(at 148.401105 102.1036 90)
		(property "Reference" "U1"
			(at -6.722433 -8.722195 0)
			(unlocked yes)
			(layer "F.SilkS")
			(effects
				(font
					(size 0.635 0.635)
					(thickness 0.1778)
				)
			)
		)
		(property "Value" "NEO-M9N-00B"
			(at -1.74154 9.661983 90)
			(unlocked yes)
			(layer "F.SilkS")
			(hide yes)
			(effects
				(font
					(size 0.635 0.635)
					(thickness 0.1778)
				)
			)
		)
		(sheetname "01-M2_NEO-M9N_MODULE")
		(sheetfile "01-M2_NEO-M9N_MODULE.kicad_sch")
		(duplicate_pad_numbers_are_jumpers no)
		(fp_line
			(start 7.1755 -8.025)
			(end 7.1755 8.025)
			(stroke
				(width 0.1778)
				(type solid)
			)
			(layer "F.SilkS")
		)
		(fp_line
			(start -7.1755 -8.025)
			(end 7.1755 -8.025)
			(stroke
				(width 0.1778)
				(type solid)
			)
			(layer "F.SilkS")
		)
		(fp_line
			(start -7.1755 -8.025)
			(end -7.1755 8.025)
			(stroke
				(width 0.1778)
				(type solid)
			)
			(layer "F.SilkS")
		)
		(fp_line
			(start -7.1755 8.025)
			(end 7.1755 8.025)
			(stroke
				(width 0.1778)
				(type solid)
			)
			(layer "F.SilkS")
		)
		(fp_rect
			(start 3.69996 8.02496)
			(end 7.17546 7.57496)
			(stroke
				(width 0)
				(type default)
			)
			(fill yes)
			(layer "F.SilkS")
		)
		(fp_rect
			(start -5.80171 -7.40111)
			(end -7.00821 -6.60101)
			(stroke
				(width 0)
				(type default)
			)
			(fill yes)
			(layer "F.Paste")
		)
		(fp_rect
			(start -4.915885 -7.299505)
			(end -5.811235 -6.702605)
			(stroke
				(width 0)
				(type default)
			)
			(fill yes)
			(layer "F.Paste")
		)
		(fp_rect
			(start 4.915555 -6.702625)
			(end 5.810905 -7.299525)
			(stroke
				(width 0)
				(type default)
			)
			(fill yes)
			(layer "F.Paste")
		)
		(fp_rect
			(start 5.80138 -6.60103)
			(end 7.00788 -7.40113)
			(stroke
				(width 0)
				(type default)
			)
			(fill yes)
			(layer "F.Paste")
		)
		(fp_rect
			(start -5.8017 -6.30105)
			(end -7.0082 -5.50095)
			(stroke
				(width 0)
				(type default)
			)
			(fill yes)
			(layer "F.Paste")
		)
		(fp_rect
			(start -4.915875 -6.199455)
			(end -5.811225 -5.602555)
			(stroke
				(width 0)
				(type default)
			)
			(fill yes)
			(layer "F.Paste")
		)
		(fp_rect
			(start 4.915575 -5.602555)
			(end 5.810925 -6.199455)
			(stroke
				(width 0)
				(type default)
			)
			(fill yes)
			(layer "F.Paste")
		)
		(fp_rect
			(start 5.8014 -5.50095)
			(end 7.0079 -6.30105)
			(stroke
				(width 0)
				(type default)
			)
			(fill yes)
			(layer "F.Paste")
		)
		(fp_rect
			(start -5.80171 -5.20111)
			(end -7.00821 -4.40101)
			(stroke
				(width 0)
				(type default)
			)
			(fill yes)
			(layer "F.Paste")
		)
		(fp_rect
			(start -4.915885 -5.099505)
			(end -5.811235 -4.502605)
			(stroke
				(width 0)
				(type default)
			)
			(fill yes)
			(layer "F.Paste")
		)
		(fp_rect
			(start 4.915555 -4.502625)
			(end 5.810905 -5.099525)
			(stroke
				(width 0)
				(type default)
			)
			(fill yes)
			(layer "F.Paste")
		)
		(fp_rect
			(start 5.80138 -4.40102)
			(end 7.00788 -5.20112)
			(stroke
				(width 0)
				(type default)
			)
			(fill yes)
			(layer "F.Paste")
		)
		(fp_rect
			(start -5.8017 -4.10105)
			(end -7.0082 -3.30095)
			(stroke
				(width 0)
				(type default)
			)
			(fill yes)
			(layer "F.Paste")
		)
		(fp_rect
			(start -4.915875 -3.999455)
			(end -5.811225 -3.402555)
			(stroke
				(width 0)
				(type default)
			)
			(fill yes)
			(layer "F.Paste")
		)
		(fp_rect
			(start 4.915575 -3.402555)
			(end 5.810925 -3.999455)
			(stroke
				(width 0)
				(type default)
			)
			(fill yes)
			(layer "F.Paste")
		)
		(fp_rect
			(start 5.8014 -3.30095)
			(end 7.0079 -4.10105)
			(stroke
				(width 0)
				(type default)
			)
			(fill yes)
			(layer "F.Paste")
		)
		(fp_rect
			(start -5.8017 -3.00105)
			(end -7.0082 -2.20095)
			(stroke
				(width 0)
				(type default)
			)
			(fill yes)
			(layer "F.Paste")
		)
		(fp_rect
			(start -4.915875 -2.899455)
			(end -5.811225 -2.302555)
			(stroke
				(width 0)
				(type default)
			)
			(fill yes)
			(layer "F.Paste")
		)
		(fp_rect
			(start 4.915575 -2.302555)
			(end 5.810925 -2.899455)
			(stroke
				(width 0)
				(type default)
			)
			(fill yes)
			(layer "F.Paste")
		)
		(fp_rect
			(start 5.8014 -2.20095)
			(end 7.0079 -3.00105)
			(stroke
				(width 0)
				(type default)
			)
			(fill yes)
			(layer "F.Paste")
		)
		(fp_rect
			(start -5.80176 -0.00103)
			(end -7.00826 0.79907)
			(stroke
				(width 0)
				(type default)
			)
			(fill yes)
			(layer "F.Paste")
		)
		(fp_rect
			(start -4.915905 0.100475)
			(end -5.811255 0.697375)
			(stroke
				(width 0)
				(type default)
			)
			(fill yes)
			(layer "F.Paste")
		)
		(fp_rect
			(start 4.915535 0.697355)
			(end 5.810885 0.100455)
			(stroke
				(width 0)
				(type default)
			)
			(fill yes)
			(layer "F.Paste")
		)
		(fp_rect
			(start 5.80134 0.79907)
			(end 7.00784 -0.00103)
			(stroke
				(width 0)
				(type default)
			)
			(fill yes)
			(layer "F.Paste")
		)
		(fp_rect
			(start -5.8017 1.09895)
			(end -7.0082 1.89905)
			(stroke
				(width 0)
				(type default)
			)
			(fill yes)
			(layer "F.Paste")
		)
		(fp_rect
			(start -4.915875 1.200545)
			(end -5.811225 1.797445)
			(stroke
				(width 0)
				(type default)
			)
			(fill yes)
			(layer "F.Paste")
		)
		(fp_rect
			(start 4.915575 1.797445)
			(end 5.810925 1.200545)
			(stroke
				(width 0)
				(type default)
			)
			(fill yes)
			(layer "F.Paste")
		)
		(fp_rect
			(start 5.8014 1.89905)
			(end 7.0079 1.09895)
			(stroke
				(width 0)
				(type default)
			)
			(fill yes)
			(layer "F.Paste")
		)
		(fp_rect
			(start -5.80173 2.19887)
			(end -7.00823 2.99897)
			(stroke
				(width 0)
				(type default)
			)
			(fill yes)
			(layer "F.Paste")
		)
		(fp_rect
			(start -4.915905 2.300475)
			(end -5.811255 2.897375)
			(stroke
				(width 0)
				(type default)
			)
			(fill yes)
			(layer "F.Paste")
		)
		(fp_rect
			(start 4.915535 2.897355)
			(end 5.810885 2.300455)
			(stroke
				(width 0)
				(type default)
			)
			(fill yes)
			(layer "F.Paste")
		)
		(fp_rect
			(start 5.80136 2.99896)
			(end 7.00786 2.19886)
			(stroke
				(width 0)
				(type default)
			)
			(fill yes)
			(layer "F.Paste")
		)
		(fp_rect
			(start -5.80173 3.29887)
			(end -7.00823 4.09897)
			(stroke
				(width 0)
				(type default)
			)
			(fill yes)
			(layer "F.Paste")
		)
		(fp_rect
			(start -4.915905 3.400465)
			(end -5.811255 3.997365)
			(stroke
				(width 0)
				(type default)
			)
			(fill yes)
			(layer "F.Paste")
		)
		(fp_rect
			(start 4.915535 3.997355)
			(end 5.810885 3.400455)
			(stroke
				(width 0)
				(type default)
			)
			(fill yes)
			(layer "F.Paste")
		)
		(fp_rect
			(start 5.80136 4.09895)
			(end 7.00786 3.29885)
			(stroke
				(width 0)
				(type default)
			)
			(fill yes)
			(layer "F.Paste")
		)
		(fp_rect
			(start -5.8017 4.39895)
			(end -7.0082 5.19905)
			(stroke
				(width 0)
				(type default)
			)
			(fill yes)
			(layer "F.Paste")
		)
		(fp_rect
			(start -4.915875 4.500545)
			(end -5.811225 5.097445)
			(stroke
				(width 0)
				(type default)
			)
			(fill yes)
			(layer "F.Paste")
		)
		(fp_rect
			(start 4.915575 5.097445)
			(end 5.810925 4.500545)
			(stroke
				(width 0)
				(type default)
			)
			(fill yes)
			(layer "F.Paste")
		)
		(fp_rect
			(start 5.8014 5.19905)
			(end 7.0079 4.39895)
			(stroke
				(width 0)
				(type default)
			)
			(fill yes)
			(layer "F.Paste")
		)
		(fp_rect
			(start -5.80173 5.49887)
			(end -7.00823 6.29897)
			(stroke
				(width 0)
				(type default)
			)
			(fill yes)
			(layer "F.Paste")
		)
		(fp_rect
			(start -4.915905 5.600465)
			(end -5.811255 6.197365)
			(stroke
				(width 0)
				(type default)
			)
			(fill yes)
			(layer "F.Paste")
		)
		(fp_rect
			(start 4.915535 6.197355)
			(end 5.810885 5.600455)
			(stroke
				(width 0)
				(type default)
			)
			(fill yes)
			(layer "F.Paste")
		)
		(fp_rect
			(start 5.80136 6.29895)
			(end 7.00786 5.49885)
			(stroke
				(width 0)
				(type default)
			)
			(fill yes)
			(layer "F.Paste")
		)
		(fp_rect
			(start -5.8017 6.59895)
			(end -7.0082 7.39905)
			(stroke
				(width 0)
				(type default)
			)
			(fill yes)
			(layer "F.Paste")
		)
		(fp_rect
			(start -4.915875 6.700545)
			(end -5.811225 7.297445)
			(stroke
				(width 0)
				(type default)
			)
			(fill yes)
			(layer "F.Paste")
		)
		(fp_rect
			(start 4.915575 7.297445)
			(end 5.810925 6.700545)
			(stroke
				(width 0)
				(type default)
			)
			(fill yes)
			(layer "F.Paste")
		)
		(fp_rect
			(start 5.8014 7.39905)
			(end 7.0079 6.59895)
			(stroke
				(width 0)
				(type default)
			)
			(fill yes)
			(layer "F.Paste")
		)
		(pad "1" smd rect
			(at 6.09981 6.99897 90)
			(size 1.79832 0.8001)
			(layers "F.Cu" "F.Mask" "F.Paste")
			(net "SAFEBOOT_N")
			(solder_paste_margin -2147.48364)
		)
		(pad "2" smd rect
			(at 6.09981 5.89915 90)
			(size 1.79832 0.8001)
			(layers "F.Cu" "F.Mask" "F.Paste")
			(net "D_SEL")
			(solder_paste_margin -2147.48364)
		)
		(pad "3" smd rect
			(at 6.09981 4.79933 90)
			(size 1.79832 0.8001)
			(layers "F.Cu" "F.Mask" "F.Paste")
			(net "TP1")
			(solder_paste_margin -2147.48364)
		)
		(pad "4" smd rect
			(at 6.09981 3.69951 90)
			(size 1.79832 0.8001)
			(layers "F.Cu" "F.Mask" "F.Paste")
			(net "EXTIN")
			(solder_paste_margin -2147.48364)
		)
		(pad "5" smd rect
			(at 6.09981 2.59969 90)
			(size 1.79832 0.8001)
			(layers "F.Cu" "F.Mask" "F.Paste")
			(net "USB_DM")
			(solder_paste_margin -2147.48364)
		)
		(pad "6" smd rect
			(at 6.09981 1.49987 90)
			(size 1.79832 0.8001)
			(layers "F.Cu" "F.Mask" "F.Paste")
			(net "USB_DP")
			(solder_paste_margin -2147.48364)
		)
		(pad "7" smd rect
			(at 6.09981 0.40005 90)
			(size 1.79832 0.8001)
			(layers "F.Cu" "F.Mask" "F.Paste")
			(net "VDD_USB")
			(solder_paste_margin -2147.48364)
		)
		(pad "8" smd rect
			(at 6.09981 -2.59969 90)
			(size 1.79832 0.8001)
			(layers "F.Cu" "F.Mask" "F.Paste")
			(net "RST_GPS")
			(solder_paste_margin -2147.48364)
		)
		(pad "9" smd rect
			(at 6.09981 -3.69951 90)
			(size 1.79832 0.8001)
			(layers "F.Cu" "F.Mask" "F.Paste")
			(solder_paste_margin -2147.48364)
		)
		(pad "10" smd rect
			(at 6.09981 -4.79933 90)
			(size 1.79832 0.8001)
			(layers "F.Cu" "F.Mask" "F.Paste")
			(net "GND")
			(solder_paste_margin -2147.48364)
		)
		(pad "11" smd rect
			(at 6.09981 -5.89915 90)
			(size 1.79832 0.8001)
			(layers "F.Cu" "F.Mask" "F.Paste")
			(net "RF_MODULE")
			(solder_paste_margin -2147.48364)
		)
		(pad "12" smd rect
			(at 6.09981 -6.99897 90)
			(size 1.79832 0.8001)
			(layers "F.Cu" "F.Mask" "F.Paste")
			(net "GND")
			(solder_paste_margin -2147.48364)
		)
		(pad "13" smd rect
			(at -6.09981 -6.99897 90)
			(size 1.79832 0.8001)
			(layers "F.Cu" "F.Mask" "F.Paste")
			(net "GND")
			(solder_paste_margin -2147.48364)
		)
		(pad "14" smd rect
			(at -6.09981 -5.89915 90)
			(size 1.79832 0.8001)
			(layers "F.Cu" "F.Mask" "F.Paste")
			(net "LNA_EN")
			(solder_paste_margin -2147.48364)
		)
		(pad "15" smd rect
			(at -6.09981 -4.79933 90)
			(size 1.79832 0.8001)
			(layers "F.Cu" "F.Mask" "F.Paste")
			(solder_paste_margin -2147.48364)
		)
		(pad "16" smd rect
			(at -6.09981 -3.69951 90)
			(size 1.79832 0.8001)
			(layers "F.Cu" "F.Mask" "F.Paste")
			(solder_paste_margin -2147.48364)
		)
		(pad "17" smd rect
			(at -6.09981 -2.59969 90)
			(size 1.79832 0.8001)
			(layers "F.Cu" "F.Mask" "F.Paste")
			(solder_paste_margin -2147.48364)
		)
		(pad "18" smd rect
			(at -6.09981 0.40005 90)
			(size 1.79832 0.8001)
			(layers "F.Cu" "F.Mask" "F.Paste")
			(net "SDA")
			(solder_paste_margin -2147.48364)
		)
		(pad "19" smd rect
			(at -6.09981 1.49987 90)
			(size 1.79832 0.8001)
			(layers "F.Cu" "F.Mask" "F.Paste")
			(net "SCL")
			(solder_paste_margin -2147.48364)
		)
		(pad "20" smd rect
			(at -6.09981 2.59969 90)
			(size 1.79832 0.8001)
			(layers "F.Cu" "F.Mask" "F.Paste")
			(net "TX_GPS")
			(solder_paste_margin -2147.48364)
		)
		(pad "21" smd rect
			(at -6.09981 3.69951 90)
			(size 1.79832 0.8001)
			(layers "F.Cu" "F.Mask" "F.Paste")
			(net "RX_GPS")
			(solder_paste_margin -2147.48364)
		)
		(pad "22" smd rect
			(at -6.09981 4.79933 90)
			(size 1.79832 0.8001)
			(layers "F.Cu" "F.Mask" "F.Paste")
			(net "+3V3")
			(solder_paste_margin -2147.48364)
		)
		(pad "23" smd rect
			(at -6.09981 5.89915 90)
			(size 1.79832 0.8001)
			(layers "F.Cu" "F.Mask" "F.Paste")
			(net "+3V3")
			(solder_paste_margin -2147.48364)
		)
		(pad "24" smd rect
			(at -6.09981 6.99897 90)
			(size 1.79832 0.8001)
			(layers "F.Cu" "F.Mask" "F.Paste")
			(net "GND")
			(solder_paste_margin -2147.48364)
		)
	)
	(footprint "Vault:RESC1005X40X25NL05T05"
		(layer "F.Cu")
		(at 146.053395 113.66797 -90)
		(property "Reference" "R16"
			(at 1.73563 0.152214 90)
			(unlocked yes)
			(layer "F.SilkS")
			(effects
				(font
					(face "Arial")
					(size 0.48006 0.48006)
					(thickness 0.254)
				)
			)
		)
		(property "Value" "1K_1%_0402"
			(at -2.759202 7.27476 180)
			(unlocked yes)
			(layer "F.SilkS")
			(hide yes)
			(effects
				(font
					(size 1.524 1.524)
					(thickness 0.254)
				)
			)
		)
		(sheetname "01-M2_NEO-M9N_MODULE")
		(sheetfile "01-M2_NEO-M9N_MODULE.kicad_sch")
		(duplicate_pad_numbers_are_jumpers no)
		(fp_line
			(start -0.89999 0.45)
			(end -0.89999 -0.45)
			(stroke
				(width 0.05)
				(type solid)
			)
			(layer "F.CrtYd")
		)
		(fp_line
			(start 0.9 0.45)
			(end -0.89999 0.45)
			(stroke
				(width 0.05)
				(type solid)
			)
			(layer "F.CrtYd")
		)
		(fp_line
			(start 0.9 0.45)
			(end 0.9 -0.45)
			(stroke
				(width 0.05)
				(type solid)
			)
			(layer "F.CrtYd")
		)
		(fp_line
			(start 0 0.275)
			(end 0 -0.275)
			(stroke
				(width 0.1)
				(type solid)
			)
			(layer "F.CrtYd")
		)
		(fp_line
			(start 0.275 0)
			(end -0.27499 0)
			(stroke
				(width 0.1)
				(type solid)
			)
			(layer "F.CrtYd")
		)
		(fp_line
			(start 0.9 -0.45)
			(end -0.89999 -0.45)
			(stroke
				(width 0.05)
				(type solid)
			)
			(layer "F.CrtYd")
		)
		(pad "1" smd rect
			(at -0.45 0)
			(size 0.55 0.55)
			(layers "F.Cu" "F.Mask" "F.Paste")
			(net "NetLED1_1")
		)
		(pad "2" smd rect
			(at 0.45001 0)
			(size 0.55 0.55)
			(layers "F.Cu" "F.Mask" "F.Paste")
			(net "+3V3")
		)
	)
	(footprint "MyLibrary:r0603"
		(layer "F.Cu")
		(at 144.201105 91.6036 180)
		(property "Reference" "R4"
			(at 0.177805 -1.377557 180)
			(unlocked yes)
			(layer "F.SilkS")
			(effects
				(font
					(size 0.635 0.635)
					(thickness 0.1778)
				)
			)
		)
		(property "Value" "10 OHM 1/4W 0603"
			(at -5.216983 5.192245 90)
			(unlocked yes)
			(layer "F.SilkS")
			(hide yes)
			(effects
				(font
					(size 0.635 0.635)
					(thickness 0.1778)
				)
			)
		)
		(sheetname "01-M2_NEO-M9N_MODULE")
		(sheetfile "01-M2_NEO-M9N_MODULE.kicad_sch")
		(duplicate_pad_numbers_are_jumpers no)
		(fp_line
			(start 1.2954 0.6858)
			(end -1.2954 0.6858)
			(stroke
				(width 0.1778)
				(type solid)
			)
			(layer "F.SilkS")
		)
		(fp_line
			(start 1.2954 -0.6858)
			(end 1.2954 0.6858)
			(stroke
				(width 0.1778)
				(type solid)
			)
			(layer "F.SilkS")
		)
		(fp_line
			(start 1.2954 -0.6858)
			(end -1.2954 -0.6858)
			(stroke
				(width 0.1778)
				(type solid)
			)
			(layer "F.SilkS")
		)
		(fp_line
			(start -1.2954 -0.6858)
			(end -1.2954 0.6858)
			(stroke
				(width 0.1778)
				(type solid)
			)
			(layer "F.SilkS")
		)
		(pad "1" smd rect
			(at -0.75 0 180)
			(size 0.6 0.9)
			(layers "F.Cu" "F.Mask" "F.Paste")
			(net "NetQ1_3")
		)
		(pad "2" smd rect
			(at 0.75 0 180)
			(size 0.6 0.9)
			(layers "F.Cu" "F.Mask" "F.Paste")
			(net "NetC5_2")
		)
	)
	(footprint "Vault:RESC1005X40X25NL05T10"
		(layer "F.Cu")
		(at 145.501105 119.1036 -90)
		(property "Reference" "R13"
			(at 0.256 -1.273069 270)
			(unlocked yes)
			(layer "F.SilkS")
			(effects
				(font
					(size 0.762 0.762)
					(thickness 0.254)
				)
			)
		)
		(property "Value" "0_5%_0402"
			(at -2.759192 6.766925 180)
			(unlocked yes)
			(layer "F.SilkS")
			(hide yes)
			(effects
				(font
					(size 1.524 1.524)
					(thickness 0.254)
				)
			)
		)
		(sheetname "02-M2_GoldFingers")
		(sheetfile "02-M2_GoldFingers.kicad_sch")
		(duplicate_pad_numbers_are_jumpers no)
		(fp_line
			(start -0.9 0.45)
			(end -0.9 -0.45)
			(stroke
				(width 0.05)
				(type solid)
			)
			(layer "F.CrtYd")
		)
		(fp_line
			(start 0.9 0.45)
			(end -0.9 0.45)
			(stroke
				(width 0.05)
				(type solid)
			)
			(layer "F.CrtYd")
		)
		(fp_line
			(start 0.9 0.45)
			(end 0.9 -0.45)
			(stroke
				(width 0.05)
				(type solid)
			)
			(layer "F.CrtYd")
		)
		(fp_line
			(start 0 0.275)
			(end 0 -0.275)
			(stroke
				(width 0.1)
				(type solid)
			)
			(layer "F.CrtYd")
		)
		(fp_line
			(start 0.275 0)
			(end -0.275 0)
			(stroke
				(width 0.1)
				(type solid)
			)
			(layer "F.CrtYd")
		)
		(fp_line
			(start 0.9 -0.45)
			(end -0.9 -0.45)
			(stroke
				(width 0.05)
				(type solid)
			)
			(layer "F.CrtYd")
		)
		(pad "1" smd rect
			(at -0.425 0)
			(size 0.55 0.6)
			(layers "F.Cu" "F.Mask" "F.Paste")
			(net "RST_GPS")
		)
		(pad "2" smd rect
			(at 0.425 0)
			(size 0.55 0.6)
			(layers "F.Cu" "F.Mask" "F.Paste")
			(net "NetJ1_50")
		)
	)
	(footprint "LotusSound:SOT23"
		(layer "F.Cu")
		(at 148.666305 90.4036 90)
		(property "Reference" "Q1"
			(at 2.477557 0.812595 0)
			(unlocked yes)
			(layer "F.SilkS")
			(effects
				(font
					(size 0.635 0.635)
					(thickness 0.1778)
				)
			)
		)
		(property "Value" "DMG2302UKQ-7"
			(at 7.883825 3.419602 90)
			(unlocked yes)
			(layer "F.SilkS")
			(hide yes)
			(effects
				(font
					(size 1.524 1.524)
					(thickness 0.254)
				)
			)
		)
		(sheetname "01-M2_NEO-M9N_MODULE")
		(sheetfile "01-M2_NEO-M9N_MODULE.kicad_sch")
		(duplicate_pad_numbers_are_jumpers no)
		(fp_line
			(start 0.5334 -1.8542)
			(end 0.5334 -0.9525)
			(stroke
				(width 0.1524)
				(type solid)
			)
			(layer "F.SilkS")
		)
		(fp_line
			(start -0.5334 -1.8542)
			(end 0.5334 -1.8542)
			(stroke
				(width 0.1524)
				(type solid)
			)
			(layer "F.SilkS")
		)
		(fp_line
			(start -0.5334 -1.8542)
			(end -0.5334 -0.9525)
			(stroke
				(width 0.1524)
				(type solid)
			)
			(layer "F.SilkS")
		)
		(fp_line
			(start 1.7526 -0.9525)
			(end 1.7526 0.9525)
			(stroke
				(width 0.1524)
				(type solid)
			)
			(layer "F.SilkS")
		)
		(fp_line
			(start 0.5334 -0.9525)
			(end 1.7526 -0.9525)
			(stroke
				(width 0.1524)
				(type solid)
			)
			(layer "F.SilkS")
		)
		(fp_line
			(start -1.7526 -0.9525)
			(end -0.5334 -0.9525)
			(stroke
				(width 0.1524)
				(type solid)
			)
			(layer "F.SilkS")
		)
		(fp_line
			(start -1.7526 -0.9525)
			(end -1.7526 0.9525)
			(stroke
				(width 0.1524)
				(type solid)
			)
			(layer "F.SilkS")
		)
		(fp_line
			(start 1.4484 0.9525)
			(end 1.7526 0.9525)
			(stroke
				(width 0.1524)
				(type solid)
			)
			(layer "F.SilkS")
		)
		(fp_line
			(start 1.4484 0.9525)
			(end 1.4484 1.8542)
			(stroke
				(width 0.1524)
				(type solid)
			)
			(layer "F.SilkS")
		)
		(fp_line
			(start -1.4484 0.9525)
			(end -1.4484 1.8542)
			(stroke
				(width 0.1524)
				(type solid)
			)
			(layer "F.SilkS")
		)
		(fp_line
			(start -1.7526 0.9525)
			(end -1.4484 0.9525)
			(stroke
				(width 0.1524)
				(type solid)
			)
			(layer "F.SilkS")
		)
		(fp_line
			(start -1.4484 1.8542)
			(end 1.4484 1.8542)
			(stroke
				(width 0.1524)
				(type solid)
			)
			(layer "F.SilkS")
		)
		(fp_circle
			(center -1.778 1.524)
			(end -1.7018 1.524)
			(stroke
				(width 0.1778)
				(type solid)
			)
			(fill no)
			(layer "F.SilkS")
		)
		(pad "1" smd rect
			(at -0.915 0.9652 90)
			(size 0.5588 1.27)
			(layers "F.Cu" "F.Mask" "F.Paste")
			(net "NetQ1_1")
		)
		(pad "2" smd rect
			(at 0.915 0.9652 90)
			(size 0.5588 1.27)
			(layers "F.Cu" "F.Mask" "F.Paste")
			(net "+3V3")
		)
		(pad "3" smd rect
			(at 0 -0.9652 90)
			(size 0.5588 1.27)
			(layers "F.Cu" "F.Mask" "F.Paste")
			(net "NetQ1_3")
		)
	)
	(footprint "MyLibrary:r0402"
		(layer "F.Cu")
		(at 142.701105 119.1036 -90)
		(property "Reference" "R8"
			(at -1.889255 0.022443 270)
			(unlocked yes)
			(layer "F.SilkS")
			(effects
				(font
					(size 0.635 0.635)
					(thickness 0.1778)
				)
			)
		)
		(property "Value" "0 ohm 0402"
			(at 2.907155 2.168983 270)
			(unlocked yes)
			(layer "F.SilkS")
			(hide yes)
			(effects
				(font
					(size 0.635 0.635)
					(thickness 0.1778)
				)
			)
		)
		(sheetname "01-M2_NEO-M9N_MODULE")
		(sheetfile "01-M2_NEO-M9N_MODULE.kicad_sch")
		(duplicate_pad_numbers_are_jumpers no)
		(fp_line
			(start -0.9906 0.5334)
			(end -0.9906 -0.5334)
			(stroke
				(width 0.1778)
				(type solid)
			)
			(layer "F.SilkS")
		)
		(fp_line
			(start 0.9906 0.5334)
			(end -0.9906 0.5334)
			(stroke
				(width 0.1778)
				(type solid)
			)
			(layer "F.SilkS")
		)
		(fp_line
			(start 0.9906 0.5334)
			(end 0.9906 -0.5334)
			(stroke
				(width 0.1778)
				(type solid)
			)
			(layer "F.SilkS")
		)
		(fp_line
			(start 0.9906 -0.5334)
			(end -0.9906 -0.5334)
			(stroke
				(width 0.1778)
				(type solid)
			)
			(layer "F.SilkS")
		)
		(pad "1" smd rect
			(at -0.5 0 270)
			(size 0.5 0.6)
			(layers "F.Cu" "F.Mask" "F.Paste")
			(net "TX_GPS")
		)
		(pad "2" smd rect
			(at 0.5 0 270)
			(size 0.5 0.6)
			(layers "F.Cu" "F.Mask" "F.Paste")
			(net "TX_GPS_CONN")
		)
	)
	(footprint "Vault:RESC1005X40X25LL05T10"
		(layer "F.Cu")
		(at 147.701105 112.7036 -90)
		(property "Reference" "R11"
			(at 1.6 0.195704 90)
			(unlocked yes)
			(layer "F.SilkS")
			(effects
				(font
					(face "Arial")
					(size 0.48006 0.48006)
					(thickness 0.254)
				)
			)
		)
		(property "Value" "10K_5%_0402"
			(at -2.606802 8.214275 180)
			(unlocked yes)
			(layer "F.SilkS")
			(hide yes)
			(effects
				(font
					(size 1.524 1.524)
					(thickness 0.254)
				)
			)
		)
		(sheetname "01-M2_NEO-M9N_MODULE")
		(sheetfile "01-M2_NEO-M9N_MODULE.kicad_sch")
		(duplicate_pad_numbers_are_jumpers no)
		(fp_line
			(start -0.75 0.4)
			(end -0.75 -0.4)
			(stroke
				(width 0.05)
				(type solid)
			)
			(layer "F.CrtYd")
		)
		(fp_line
			(start 0.75 0.4)
			(end -0.75 0.4)
			(stroke
				(width 0.05)
				(type solid)
			)
			(layer "F.CrtYd")
		)
		(fp_line
			(start 0.75 0.4)
			(end 0.75 -0.4)
			(stroke
				(width 0.05)
				(type solid)
			)
			(layer "F.CrtYd")
		)
		(fp_line
			(start 0 0.275)
			(end 0 -0.275)
			(stroke
				(width 0.1)
				(type solid)
			)
			(layer "F.CrtYd")
		)
		(fp_line
			(start 0.275 0)
			(end -0.275 0)
			(stroke
				(width 0.1)
				(type solid)
			)
			(layer "F.CrtYd")
		)
		(fp_line
			(start 0.75 -0.4)
			(end -0.75 -0.4)
			(stroke
				(width 0.05)
				(type solid)
			)
			(layer "F.CrtYd")
		)
		(pad "1" smd rect
			(at -0.375 0)
			(size 0.45 0.5)
			(layers "F.Cu" "F.Mask" "F.Paste")
			(net "SDA")
		)
		(pad "2" smd rect
			(at 0.375 0)
			(size 0.45 0.5)
			(layers "F.Cu" "F.Mask" "F.Paste")
			(net "+3V3")
		)
	)
	(footprint "MyLibrary:TP1MM"
		(layer "F.Cu")
		(at 149.301105 93.5036)
		(property "Reference" "TP4"
			(at 1.630785 -0.332727 0)
			(unlocked yes)
			(layer "F.SilkS")
			(effects
				(font
					(size 0.635 0.635)
					(thickness 0.1778)
				)
			)
		)
		(property "Value" "1MM"
			(at -2.092793 1.790085 270)
			(unlocked yes)
			(layer "F.SilkS")
			(hide yes)
			(effects
				(font
					(size 0.635 0.635)
					(thickness 0.1778)
				)
			)
		)
		(sheetname "01-M2_NEO-M9N_MODULE")
		(sheetfile "01-M2_NEO-M9N_MODULE.kicad_sch")
		(duplicate_pad_numbers_are_jumpers no)
		(pad "1" smd circle
			(at 0 0)
			(size 1 1)
			(layers "F.Cu" "F.Mask" "F.Paste")
			(net "VDD_USB")
			(solder_paste_margin -100)
			(thermal_bridge_angle 90)
		)
	)
	(footprint "MyLibrary:r0402"
		(layer "F.Cu")
		(at 156.501105 92.0036 -90)
		(property "Reference" "R10"
			(at 0.227805 -1.377557 270)
			(unlocked yes)
			(layer "F.SilkS")
			(effects
				(font
					(size 0.635 0.635)
					(thickness 0.1778)
				)
			)
		)
		(property "Value" "DNI 0 ohm 0402"
			(at 2.90715 2.168983 270)
			(unlocked yes)
			(layer "F.SilkS")
			(hide yes)
			(effects
				(font
					(size 0.635 0.635)
					(thickness 0.1778)
				)
			)
		)
		(sheetname "01-M2_NEO-M9N_MODULE")
		(sheetfile "01-M2_NEO-M9N_MODULE.kicad_sch")
		(duplicate_pad_numbers_are_jumpers no)
		(fp_line
			(start -0.9906 0.5334)
			(end -0.9906 -0.5334)
			(stroke
				(width 0.1778)
				(type solid)
			)
			(layer "F.SilkS")
		)
		(fp_line
			(start 0.9906 0.5334)
			(end -0.9906 0.5334)
			(stroke
				(width 0.1778)
				(type solid)
			)
			(layer "F.SilkS")
		)
		(fp_line
			(start 0.9906 0.5334)
			(end 0.9906 -0.5334)
			(stroke
				(width 0.1778)
				(type solid)
			)
			(layer "F.SilkS")
		)
		(fp_line
			(start 0.9906 -0.5334)
			(end -0.9906 -0.5334)
			(stroke
				(width 0.1778)
				(type solid)
			)
			(layer "F.SilkS")
		)
		(pad "1" smd rect
			(at -0.5 0 270)
			(size 0.5 0.6)
			(layers "F.Cu" "F.Mask" "F.Paste")
			(net "GND")
		)
		(pad "2" smd rect
			(at 0.5 0 270)
			(size 0.5 0.6)
			(layers "F.Cu" "F.Mask" "F.Paste")
			(net "D_SEL")
		)
	)
	(footprint "MyLibrary:led0603"
		(layer "F.Cu")
		(at 149.501105 117.2036)
		(property "Reference" "LED2"
			(at 0.3278 1.322443 0)
			(unlocked yes)
			(layer "F.SilkS")
			(effects
				(font
					(size 0.635 0.635)
					(thickness 0.1778)
				)
			)
		)
		(property "Value" "Green"
			(at -3.032583 3.262745 270)
			(unlocked yes)
			(layer "F.SilkS")
			(hide yes)
			(effects
				(font
					(size 0.635 0.635)
					(thickness 0.1778)
				)
			)
		)
		(sheetname "01-M2_NEO-M9N_MODULE")
		(sheetfile "01-M2_NEO-M9N_MODULE.kicad_sch")
		(duplicate_pad_numbers_are_jumpers no)
		(fp_line
			(start -1.397 -0.635)
			(end 1.397 -0.635)
			(stroke
				(width 0.1778)
				(type solid)
			)
			(layer "F.SilkS")
		)
		(fp_line
			(start -1.397 0.635)
			(end -1.397 -0.635)
			(stroke
				(width 0.1778)
				(type solid)
			)
			(layer "F.SilkS")
		)
		(fp_line
			(start -1.397 0.635)
			(end 1.397 0.635)
			(stroke
				(width 0.1778)
				(type solid)
			)
			(layer "F.SilkS")
		)
		(fp_line
			(start -0.03175 -0.12065)
			(end 0.08255 -0.00635)
			(stroke
				(width 0.0762)
				(type solid)
			)
			(layer "F.SilkS")
		)
		(fp_line
			(start -0.03175 0.10795)
			(end -0.03175 -0.12065)
			(stroke
				(width 0.0762)
				(type solid)
			)
			(layer "F.SilkS")
		)
		(fp_line
			(start -0.03175 0.10795)
			(end 0.08255 -0.00635)
			(stroke
				(width 0.0762)
				(type solid)
			)
			(layer "F.SilkS")
		)
		(fp_line
			(start 1.397 0.635)
			(end 1.397 -0.635)
			(stroke
				(width 0.1778)
				(type solid)
			)
			(layer "F.SilkS")
		)
		(fp_rect
			(start -0.03203 0.04819)
			(end 0.03705 -0.05276)
			(stroke
				(width 0)
				(type default)
			)
			(fill yes)
			(layer "F.SilkS")
		)
		(pad "1" smd rect
			(at -0.75 0)
			(size 0.8 0.8)
			(layers "F.Cu" "F.Mask" "F.Paste")
			(net "+3V3")
		)
		(pad "2" smd rect
			(at 0.75 0)
			(size 0.8 0.8)
			(layers "F.Cu" "F.Mask" "F.Paste")
			(net "NetLED2_2")
		)
	)
	(footprint "M2_Library:OCPTAP M2 FINGERS"
		(locked yes)
		(layer "F.Cu")
		(at 157.751105 124.7286)
		(property "Reference" "J1"
			(at -0.741195 -2.202557 0)
			(unlocked yes)
			(layer "F.SilkS")
			(effects
				(font
					(size 0.635 0.635)
					(thickness 0.1778)
				)
			)
		)
		(property "Value" "OCPTAP_M2_FINGERS"
			(at 7.908735 8.542283 0)
			(unlocked yes)
			(layer "F.SilkS")
			(hide yes)
			(effects
				(font
					(size 0.635 0.635)
					(thickness 0.1778)
				)
			)
		)
		(sheetname "02-M2_GoldFingers")
		(sheetfile "02-M2_GoldFingers.kicad_sch")
		(duplicate_pad_numbers_are_jumpers no)
		(fp_text user "75"
			(at -18.81125 -1.625 270)
			(unlocked yes)
			(layer "F.SilkS")
			(effects
				(font
					(size 0.5 0.5)
					(thickness 0.1)
				)
				(justify left bottom mirror)
			)
		)
		(fp_text user "21"
			(at -5.13625 -1.55001 270)
			(unlocked yes)
			(layer "F.SilkS")
			(effects
				(font
					(size 0.5 0.5)
					(thickness 0.1)
				)
				(justify left bottom mirror)
			)
		)
		(fp_text user "11"
			(at -2.81125 -1.50002 270)
			(unlocked yes)
			(layer "F.SilkS")
			(effects
				(font
					(size 0.5 0.5)
					(thickness 0.1)
				)
				(justify left bottom mirror)
			)
		)
		(fp_text user "1"
			(at -0.20525 -1.475 270)
			(unlocked yes)
			(layer "F.SilkS")
			(effects
				(font
					(size 0.5 0.5)
					(thickness 0.1)
				)
				(justify left bottom mirror)
			)
		)
		(fp_text user "74"
			(at -18.61125 -1.625 270)
			(unlocked yes)
			(layer "B.SilkS")
			(effects
				(font
					(size 0.5 0.5)
					(thickness 0.1)
				)
				(justify left bottom mirror)
			)
		)
		(fp_text user "20"
			(at -5.21125 -1.425 270)
			(unlocked yes)
			(layer "B.SilkS")
			(effects
				(font
					(size 0.5 0.5)
					(thickness 0.1)
				)
				(justify left bottom mirror)
			)
		)
		(fp_text user "10"
			(at -2.61125 -1.525 270)
			(unlocked yes)
			(layer "B.SilkS")
			(effects
				(font
					(size 0.5 0.5)
					(thickness 0.1)
				)
				(justify left bottom mirror)
			)
		)
		(fp_text user "2"
			(at -0.27841 -1.725 270)
			(unlocked yes)
			(layer "B.SilkS")
			(effects
				(font
					(size 0.5 0.5)
					(thickness 0.1)
				)
				(justify left bottom mirror)
			)
		)
		(pad "1" smd rect
			(at 0 0)
			(size 0.35 1.45)
			(layers "F.Cu" "F.Mask" "F.Paste")
		)
		(pad "2" smd rect
			(at -0.244 -0.25)
			(size 0.35 1.95)
			(layers "B.Cu" "B.Mask" "B.Paste")
			(net "+3V3")
		)
		(pad "3" smd rect
			(at -0.5 0)
			(size 0.35 1.45)
			(layers "F.Cu" "F.Mask" "F.Paste")
			(net "GND")
		)
		(pad "4" smd rect
			(at -0.744 -0.25)
			(size 0.35 1.95)
			(layers "B.Cu" "B.Mask" "B.Paste")
			(net "+3V3")
		)
		(pad "5" smd rect
			(at -1 0)
			(size 0.35 1.45)
			(layers "F.Cu" "F.Mask" "F.Paste")
			(net "GND")
		)
		(pad "6" smd rect
			(at -1.244 -0.25)
			(size 0.35 1.95)
			(layers "B.Cu" "B.Mask" "B.Paste")
		)
		(pad "7" smd rect
			(at -1.5 0)
			(size 0.35 1.45)
			(layers "F.Cu" "F.Mask" "F.Paste")
			(net "USB_DP")
		)
		(pad "8" smd rect
			(at -1.744 -0.25)
			(size 0.35 1.95)
			(layers "B.Cu" "B.Mask" "B.Paste")
		)
		(pad "9" smd rect
			(at -2 0)
			(size 0.35 1.45)
			(layers "F.Cu" "F.Mask" "F.Paste")
			(net "USB_DM")
		)
		(pad "10" smd rect
			(at -2.244 -0.25)
			(size 0.35 1.95)
			(layers "B.Cu" "B.Mask" "B.Paste")
		)
		(pad "11" smd rect
			(at -2.5 0)
			(size 0.35 1.45)
			(layers "F.Cu" "F.Mask" "F.Paste")
			(net "GND")
		)
		(pad "20" smd rect
			(at -4.744 -0.25)
			(size 0.35 1.95)
			(layers "B.Cu" "B.Mask" "B.Paste")
		)
		(pad "21" smd rect
			(at -5 0)
			(size 0.35 1.45)
			(layers "F.Cu" "F.Mask" "F.Paste")
			(net "GND")
		)
		(pad "22" smd rect
			(at -5.244 -0.25)
			(size 0.35 1.95)
			(layers "B.Cu" "B.Mask" "B.Paste")
		)
		(pad "23" smd rect
			(at -5.5 0)
			(size 0.35 1.45)
			(layers "F.Cu" "F.Mask" "F.Paste")
		)
		(pad "24" smd rect
			(at -5.744 -0.25)
			(size 0.35 1.95)
			(layers "B.Cu" "B.Mask" "B.Paste")
		)
		(pad "25" smd rect
			(at -6 0)
			(size 0.35 1.45)
			(layers "F.Cu" "F.Mask" "F.Paste")
		)
		(pad "26" smd rect
			(at -6.244 -0.25)
			(size 0.35 1.95)
			(layers "B.Cu" "B.Mask" "B.Paste")
		)
		(pad "27" smd rect
			(at -6.5 0)
			(size 0.35 1.45)
			(layers "F.Cu" "F.Mask" "F.Paste")
			(net "GND")
		)
		(pad "28" smd rect
			(at -6.744 -0.25)
			(size 0.35 1.95)
			(layers "B.Cu" "B.Mask" "B.Paste")
		)
		(pad "29" smd rect
			(at -7 0)
			(size 0.35 1.45)
			(layers "F.Cu" "F.Mask" "F.Paste")
		)
		(pad "30" smd rect
			(at -7.244 -0.25)
			(size 0.35 1.95)
			(layers "B.Cu" "B.Mask" "B.Paste")
		)
		(pad "31" smd rect
			(at -7.5 0)
			(size 0.35 1.45)
			(layers "F.Cu" "F.Mask" "F.Paste")
		)
		(pad "32" smd rect
			(at -7.744 -0.25)
			(size 0.35 1.95)
			(layers "B.Cu" "B.Mask" "B.Paste")
		)
		(pad "33" smd rect
			(at -8 0)
			(size 0.35 1.45)
			(layers "F.Cu" "F.Mask" "F.Paste")
			(net "GND")
		)
		(pad "34" smd rect
			(at -8.244 -0.25)
			(size 0.35 1.95)
			(layers "B.Cu" "B.Mask" "B.Paste")
		)
		(pad "35" smd rect
			(at -8.5 0)
			(size 0.35 1.45)
			(layers "F.Cu" "F.Mask" "F.Paste")
			(net "NetJ1_35")
		)
		(pad "36" smd rect
			(at -8.744 -0.25)
			(size 0.35 1.95)
			(layers "B.Cu" "B.Mask" "B.Paste")
		)
		(pad "37" smd rect
			(at -9 0)
			(size 0.35 1.45)
			(layers "F.Cu" "F.Mask" "F.Paste")
		)
		(pad "38" smd rect
			(at -9.244 -0.25)
			(size 0.35 1.95)
			(layers "B.Cu" "B.Mask" "B.Paste")
		)
		(pad "39" smd rect
			(at -9.5 0)
			(size 0.35 1.45)
			(layers "F.Cu" "F.Mask" "F.Paste")
			(net "GND")
		)
		(pad "40" smd rect
			(at -9.744 -0.25)
			(size 0.35 1.95)
			(layers "B.Cu" "B.Mask" "B.Paste")
			(net "SCL")
		)
		(pad "41" smd rect
			(at -10 0)
			(size 0.35 1.45)
			(layers "F.Cu" "F.Mask" "F.Paste")
		)
		(pad "42" smd rect
			(at -10.244 -0.25)
			(size 0.35 1.95)
			(layers "B.Cu" "B.Mask" "B.Paste")
			(net "SDA")
		)
		(pad "43" smd rect
			(at -10.5 0)
			(size 0.35 1.45)
			(layers "F.Cu" "F.Mask" "F.Paste")
		)
		(pad "44" smd rect
			(at -10.744 -0.25)
			(size 0.35 1.95)
			(layers "B.Cu" "B.Mask" "B.Paste")
		)
		(pad "45" smd rect
			(at -11 0)
			(size 0.35 1.45)
			(layers "F.Cu" "F.Mask" "F.Paste")
			(net "GND")
		)
		(pad "46" smd rect
			(at -11.244 -0.25)
			(size 0.35 1.95)
			(layers "B.Cu" "B.Mask" "B.Paste")
			(net "NetJ1_46")
		)
		(pad "47" smd rect
			(at -11.5 0)
			(size 0.35 1.45)
			(layers "F.Cu" "F.Mask" "F.Paste")
		)
		(pad "48" smd rect
			(at -11.744 -0.25)
			(size 0.35 1.95)
			(layers "B.Cu" "B.Mask" "B.Paste")
		)
		(pad "49" smd rect
			(at -12 0)
			(size 0.35 1.45)
			(layers "F.Cu" "F.Mask" "F.Paste")
		)
		(pad "50" smd rect
			(at -12.244 -0.25)
			(size 0.35 1.95)
			(layers "B.Cu" "B.Mask" "B.Paste")
			(net "NetJ1_50")
		)
		(pad "51" smd rect
			(at -12.5 0)
			(size 0.35 1.45)
			(layers "F.Cu" "F.Mask" "F.Paste")
			(net "GND")
		)
		(pad "52" smd rect
			(at -12.744 -0.25)
			(size 0.35 1.95)
			(layers "B.Cu" "B.Mask" "B.Paste")
		)
		(pad "53" smd rect
			(at -13 0)
			(size 0.35 1.45)
			(layers "F.Cu" "F.Mask" "F.Paste")
		)
		(pad "54" smd rect
			(at -13.244 -0.25)
			(size 0.35 1.95)
			(layers "B.Cu" "B.Mask" "B.Paste")
		)
		(pad "55" smd rect
			(at -13.5 0)
			(size 0.35 1.45)
			(layers "F.Cu" "F.Mask" "F.Paste")
		)
		(pad "56" smd rect
			(at -13.744 -0.25)
			(size 0.35 1.95)
			(layers "B.Cu" "B.Mask" "B.Paste")
		)
		(pad "57" smd rect
			(at -14 0)
			(size 0.35 1.45)
			(layers "F.Cu" "F.Mask" "F.Paste")
			(net "GND")
		)
		(pad "58" smd rect
			(at -14.244 -0.25)
			(size 0.35 1.95)
			(layers "B.Cu" "B.Mask" "B.Paste")
		)
		(pad "59" smd rect
			(at -14.5 0)
			(size 0.35 1.45)
			(layers "F.Cu" "F.Mask" "F.Paste")
		)
		(pad "60" smd rect
			(at -14.744 -0.25)
			(size 0.35 1.95)
			(layers "B.Cu" "B.Mask" "B.Paste")
		)
		(pad "61" smd rect
			(at -15 0)
			(size 0.35 1.45)
			(layers "F.Cu" "F.Mask" "F.Paste")
		)
		(pad "62" smd rect
			(at -15.244 -0.25)
			(size 0.35 1.95)
			(layers "B.Cu" "B.Mask" "B.Paste")
			(net "RX_GPS_CONN")
		)
		(pad "63" smd rect
			(at -15.5 0)
			(size 0.35 1.45)
			(layers "F.Cu" "F.Mask" "F.Paste")
		)
		(pad "64" smd rect
			(at -15.744 -0.25)
			(size 0.35 1.95)
			(layers "B.Cu" "B.Mask" "B.Paste")
			(net "TX_GPS_CONN")
		)
		(pad "65" smd rect
			(at -16 0)
			(size 0.35 1.45)
			(layers "F.Cu" "F.Mask" "F.Paste")
		)
		(pad "66" smd rect
			(at -16.244 -0.25)
			(size 0.35 1.95)
			(layers "B.Cu" "B.Mask" "B.Paste")
		)
		(pad "67" smd rect
			(at -16.5 0)
			(size 0.35 1.45)
			(layers "F.Cu" "F.Mask" "F.Paste")
			(net "NetJ1_67")
		)
		(pad "68" smd rect
			(at -16.744 -0.25)
			(size 0.35 1.95)
			(layers "B.Cu" "B.Mask" "B.Paste")
		)
		(pad "69" smd rect
			(at -17 0)
			(size 0.35 1.45)
			(layers "F.Cu" "F.Mask" "F.Paste")
		)
		(pad "70" smd rect
			(at -17.244 -0.25)
			(size 0.35 1.95)
			(layers "B.Cu" "B.Mask" "B.Paste")
			(net "+3V3")
		)
		(pad "71" smd rect
			(at -17.5 0)
			(size 0.35 1.45)
			(layers "F.Cu" "F.Mask" "F.Paste")
			(net "GND")
		)
		(pad "72" smd rect
			(at -17.744 -0.25)
			(size 0.35 1.95)
			(layers "B.Cu" "B.Mask" "B.Paste")
			(net "+3V3")
		)
		(pad "73" smd rect
			(at -18 0)
			(size 0.35 1.45)
			(layers "F.Cu" "F.Mask" "F.Paste")
			(net "GND")
		)
		(pad "74" smd rect
			(at -18.244 -0.25)
			(size 0.35 1.95)
			(layers "B.Cu" "B.Mask" "B.Paste")
			(net "+3V3")
		)
		(pad "75" smd rect
			(at -18.5 0)
			(size 0.35 1.45)
			(layers "F.Cu" "F.Mask" "F.Paste")
			(net "GND")
		)
	)
	(footprint "MyLibrary:r0402"
		(layer "F.Cu")
		(at 147.501105 93.6036 180)
		(property "Reference" "R1"
			(at 0.622205 1.177557 0)
			(unlocked yes)
			(layer "F.SilkS")
			(effects
				(font
					(size 0.635 0.635)
					(thickness 0.1778)
				)
			)
		)
		(property "Value" "0 ohm 0402"
			(at 2.907155 2.168983 180)
			(unlocked yes)
			(layer "F.SilkS")
			(hide yes)
			(effects
				(font
					(size 0.635 0.635)
					(thickness 0.1778)
				)
			)
		)
		(sheetname "01-M2_NEO-M9N_MODULE")
		(sheetfile "01-M2_NEO-M9N_MODULE.kicad_sch")
		(duplicate_pad_numbers_are_jumpers no)
		(fp_line
			(start 0.9906 0.5334)
			(end -0.9906 0.5334)
			(stroke
				(width 0.1778)
				(type solid)
			)
			(layer "F.SilkS")
		)
		(fp_line
			(start 0.9906 -0.5334)
			(end 0.9906 0.5334)
			(stroke
				(width 0.1778)
				(type solid)
			)
			(layer "F.SilkS")
		)
		(fp_line
			(start 0.9906 -0.5334)
			(end -0.9906 -0.5334)
			(stroke
				(width 0.1778)
				(type solid)
			)
			(layer "F.SilkS")
		)
		(fp_line
			(start -0.9906 -0.5334)
			(end -0.9906 0.5334)
			(stroke
				(width 0.1778)
				(type solid)
			)
			(layer "F.SilkS")
		)
		(pad "1" smd rect
			(at -0.5 0 180)
			(size 0.5 0.6)
			(layers "F.Cu" "F.Mask" "F.Paste")
			(net "VDD_USB")
		)
		(pad "2" smd rect
			(at 0.5 0 180)
			(size 0.5 0.6)
			(layers "F.Cu" "F.Mask" "F.Paste")
			(net "GND")
		)
	)
	(footprint "MyLibrary:c0402"
		(layer "F.Cu")
		(at 154.901105 111.2036 180)
		(property "Reference" "C2"
			(at -1.977795 -0.022443 0)
			(unlocked yes)
			(layer "F.SilkS")
			(effects
				(font
					(size 0.635 0.635)
					(thickness 0.1778)
				)
			)
		)
		(property "Value" "100nF 10V 0402"
			(at 5.700245 2.118183 180)
			(unlocked yes)
			(layer "F.SilkS")
			(hide yes)
			(effects
				(font
					(size 0.635 0.635)
					(thickness 0.1778)
				)
			)
		)
		(sheetname "01-M2_NEO-M9N_MODULE")
		(sheetfile "01-M2_NEO-M9N_MODULE.kicad_sch")
		(duplicate_pad_numbers_are_jumpers no)
		(fp_line
			(start 0.9906 0.4826)
			(end -0.9906 0.4826)
			(stroke
				(width 0.1778)
				(type solid)
			)
			(layer "F.SilkS")
		)
		(fp_line
			(start 0.9906 -0.4826)
			(end 0.9906 0.4826)
			(stroke
				(width 0.1778)
				(type solid)
			)
			(layer "F.SilkS")
		)
		(fp_line
			(start 0.9906 -0.4826)
			(end -0.9906 -0.4826)
			(stroke
				(width 0.1778)
				(type solid)
			)
			(layer "F.SilkS")
		)
		(fp_line
			(start -0.9906 -0.4826)
			(end -0.9906 0.4826)
			(stroke
				(width 0.1778)
				(type solid)
			)
			(layer "F.SilkS")
		)
		(pad "1" smd rect
			(at -0.5 0 180)
			(size 0.5 0.5)
			(layers "F.Cu" "F.Mask" "F.Paste")
			(net "GND")
		)
		(pad "2" smd rect
			(at 0.5 0 180)
			(size 0.5 0.5)
			(layers "F.Cu" "F.Mask" "F.Paste")
			(net "+3V3")
		)
	)
	(footprint "Vault:FP-LQG15HH_02-IPC_C"
		(layer "F.Cu")
		(at 141.801105 90.0036 180)
		(property "Reference" "L1"
			(at 1.822195 0.077557 0)
			(unlocked yes)
			(layer "F.SilkS")
			(effects
				(font
					(size 0.635 0.635)
					(thickness 0.1778)
				)
			)
		)
		(property "Value" "27nH 350mA 0.46ohm 0402"
			(at 12.962345 2.118183 180)
			(unlocked yes)
			(layer "F.SilkS")
			(hide yes)
			(effects
				(font
					(size 0.635 0.635)
					(thickness 0.1778)
				)
			)
		)
		(sheetname "01-M2_NEO-M9N_MODULE")
		(sheetfile "01-M2_NEO-M9N_MODULE.kicad_sch")
		(duplicate_pad_numbers_are_jumpers no)
		(fp_line
			(start 0.63624 0.675)
			(end -0.63624 0.675)
			(stroke
				(width 0.2)
				(type solid)
			)
			(layer "F.SilkS")
		)
		(fp_line
			(start 0.63624 -0.675)
			(end -0.63624 -0.675)
			(stroke
				(width 0.2)
				(type solid)
			)
			(layer "F.SilkS")
		)
		(fp_circle
			(center -0.8 1.3)
			(end -0.8 1.425)
			(stroke
				(width 0.25)
				(type solid)
			)
			(fill no)
			(layer "F.SilkS")
		)
		(fp_line
			(start 0.73624 0.375)
			(end -0.73624 0.375)
			(stroke
				(width 0.2)
				(type solid)
			)
			(layer "F.CrtYd")
		)
		(fp_line
			(start 0.73624 -0.375)
			(end 0.73624 0.375)
			(stroke
				(width 0.2)
				(type solid)
			)
			(layer "F.CrtYd")
		)
		(fp_line
			(start 0.73624 -0.375)
			(end -0.73624 -0.375)
			(stroke
				(width 0.2)
				(type solid)
			)
			(layer "F.CrtYd")
		)
		(fp_line
			(start -0.73624 -0.375)
			(end -0.73624 0.375)
			(stroke
				(width 0.2)
				(type solid)
			)
			(layer "F.CrtYd")
		)
		(fp_line
			(start 0.73624 0.375)
			(end -0.73624 0.375)
			(stroke
				(width 0.2)
				(type solid)
			)
			(layer "F.Fab")
		)
		(fp_line
			(start 0.73624 -0.375)
			(end 0.73624 0.375)
			(stroke
				(width 0.2)
				(type solid)
			)
			(layer "F.Fab")
		)
		(fp_line
			(start 0.73624 -0.375)
			(end -0.73624 -0.375)
			(stroke
				(width 0.2)
				(type solid)
			)
			(layer "F.Fab")
		)
		(fp_line
			(start 0.5 0)
			(end -0.5 0)
			(stroke
				(width 0.1)
				(type solid)
			)
			(layer "F.Fab")
		)
		(fp_line
			(start 0 -0.5)
			(end 0 0.5)
			(stroke
				(width 0.1)
				(type solid)
			)
			(layer "F.Fab")
		)
		(fp_line
			(start -0.73624 -0.375)
			(end -0.73624 0.375)
			(stroke
				(width 0.2)
				(type solid)
			)
			(layer "F.Fab")
		)
		(fp_text user "${REFERENCE}"
			(at 0.00001 0.29534 180)
			(unlocked yes)
			(layer "F.Fab")
			(effects
				(font
					(face "Arial")
					(size 0.63 0.63)
					(thickness 0.1)
				)
				(justify left bottom)
			)
		)
		(pad "1" smd rect
			(at -0.37856 0 180)
			(size 0.51535 0.47247)
			(layers "F.Cu" "F.Mask" "F.Paste")
			(net "NetC5_2")
			(solder_mask_margin 0)
			(solder_paste_margin 0)
		)
		(pad "2" smd rect
			(at 0.37857 0 180)
			(size 0.51535 0.47247)
			(layers "F.Cu" "F.Mask" "F.Paste")
			(net "RF_ANT")
			(solder_mask_margin 0)
			(solder_paste_margin 0)
		)
	)
	(footprint "Vault:FP-419AB-01-IPC_C"
		(layer "F.Cu")
		(at 143.801105 112.0036 90)
		(property "Reference" "Q2"
			(at 1.722239 -2.679935 360)
			(unlocked yes)
			(layer "F.SilkS")
			(effects
				(font
					(face "Arial")
					(size 0.96012 0.96012)
					(thickness 0.254)
				)
			)
		)
		(property "Value" "2N7002W"
			(at 4.02426 2.937002 90)
			(unlocked yes)
			(layer "F.SilkS")
			(hide yes)
			(effects
				(font
					(size 1.524 1.524)
					(thickness 0.254)
				)
			)
		)
		(sheetname "01-M2_NEO-M9N_MODULE")
		(sheetfile "01-M2_NEO-M9N_MODULE.kicad_sch")
		(duplicate_pad_numbers_are_jumpers no)
		(fp_line
			(start -1.05 -1.25)
			(end 1.05 -1.25)
			(stroke
				(width 0.2)
				(type solid)
			)
			(layer "F.SilkS")
		)
		(fp_line
			(start -1.05 1.25)
			(end 1.05 1.25)
			(stroke
				(width 0.2)
				(type solid)
			)
			(layer "F.SilkS")
		)
		(fp_line
			(start 1.45207 -1.1)
			(end 1.45207 1.1)
			(stroke
				(width 0.2)
				(type solid)
			)
			(layer "F.CrtYd")
		)
		(fp_line
			(start -1.45208 -1.1)
			(end 1.45207 -1.1)
			(stroke
				(width 0.2)
				(type solid)
			)
			(layer "F.CrtYd")
		)
		(fp_line
			(start -1.45208 -1.1)
			(end -1.45208 1.1)
			(stroke
				(width 0.2)
				(type solid)
			)
			(layer "F.CrtYd")
		)
		(fp_line
			(start -1.45208 1.1)
			(end 1.45207 1.1)
			(stroke
				(width 0.2)
				(type solid)
			)
			(layer "F.CrtYd")
		)
		(fp_line
			(start 1.45207 -1.1)
			(end 1.45207 1.1)
			(stroke
				(width 0.2)
				(type solid)
			)
			(layer "F.Fab")
		)
		(fp_line
			(start -1.45208 -1.1)
			(end 1.45207 -1.1)
			(stroke
				(width 0.2)
				(type solid)
			)
			(layer "F.Fab")
		)
		(fp_line
			(start -1.45208 -1.1)
			(end -1.45208 1.1)
			(stroke
				(width 0.2)
				(type solid)
			)
			(layer "F.Fab")
		)
		(fp_line
			(start 0 -0.5)
			(end 0 0.5)
			(stroke
				(width 0.1)
				(type solid)
			)
			(layer "F.Fab")
		)
		(fp_line
			(start -0.5 0)
			(end 0.5 0)
			(stroke
				(width 0.1)
				(type solid)
			)
			(layer "F.Fab")
		)
		(fp_line
			(start -1.45208 1.1)
			(end 1.45207 1.1)
			(stroke
				(width 0.2)
				(type solid)
			)
			(layer "F.Fab")
		)
		(fp_text user "${REFERENCE}"
			(at -0.00001 0.05719 90)
			(unlocked yes)
			(layer "F.Fab")
			(effects
				(font
					(face "Arial")
					(size 0.63 0.63)
					(thickness 0.1)
				)
				(justify left bottom)
			)
		)
		(pad "1" smd rect
			(at -0.7701 -0.65 90)
			(size 1.16396 0.33583)
			(layers "F.Cu" "F.Mask" "F.Paste")
			(net "TP1")
			(solder_mask_margin 0)
			(solder_paste_margin 0)
		)
		(pad "2" smd roundrect
			(at -0.7701 0.65 90)
			(size 1.16396 0.33583)
			(layers "F.Cu" "F.Mask" "F.Paste")
			(roundrect_rratio 0.5)
			(net "GND")
			(solder_mask_margin 0)
			(solder_paste_margin 0)
		)
		(pad "3" smd roundrect
			(at 0.7701 0 90)
			(size 1.16396 0.33583)
			(layers "F.Cu" "F.Mask" "F.Paste")
			(roundrect_rratio 0.5)
			(net "NetLED1_2")
			(solder_mask_margin 0)
			(solder_paste_margin 0)
		)
	)
	(footprint "MyLibrary:TP1MM"
		(layer "F.Cu")
		(at 149.301105 110.6036)
		(property "Reference" "TP9"
			(at -0.783125 1.100005 90)
			(unlocked yes)
			(layer "F.SilkS")
			(effects
				(font
					(face "Arial")
					(size 0.40005 0.40005)
					(thickness 0.1778)
				)
			)
		)
		(property "Value" "1MM"
			(at -2.092783 1.790085 270)
			(unlocked yes)
			(layer "F.SilkS")
			(hide yes)
			(effects
				(font
					(size 0.635 0.635)
					(thickness 0.1778)
				)
			)
		)
		(sheetname "01-M2_NEO-M9N_MODULE")
		(sheetfile "01-M2_NEO-M9N_MODULE.kicad_sch")
		(duplicate_pad_numbers_are_jumpers no)
		(pad "1" smd circle
			(at 0 0)
			(size 1 1)
			(layers "F.Cu" "F.Mask" "F.Paste")
			(net "SCL")
			(solder_paste_margin -100)
			(thermal_bridge_angle 90)
		)
	)
	(footprint "MyLibrary:TP1MM"
		(layer "F.Cu")
		(at 147.901105 110.6036)
		(property "Reference" "TP8"
			(at -0.783125 1.000005 90)
			(unlocked yes)
			(layer "F.SilkS")
			(effects
				(font
					(face "Arial")
					(size 0.40005 0.40005)
					(thickness 0.1778)
				)
			)
		)
		(property "Value" "1MM"
			(at -2.092783 1.790085 270)
			(unlocked yes)
			(layer "F.SilkS")
			(hide yes)
			(effects
				(font
					(size 0.635 0.635)
					(thickness 0.1778)
				)
			)
		)
		(sheetname "01-M2_NEO-M9N_MODULE")
		(sheetfile "01-M2_NEO-M9N_MODULE.kicad_sch")
		(duplicate_pad_numbers_are_jumpers no)
		(pad "1" smd circle
			(at 0 0)
			(size 1 1)
			(layers "F.Cu" "F.Mask" "F.Paste")
			(net "SDA")
			(solder_paste_margin -100)
			(thermal_bridge_angle 90)
		)
	)
	(footprint "MyLibrary:TP1MM"
		(layer "F.Cu")
		(at 150.701105 110.6036 90)
		(property "Reference" "TP11"
			(at -1.92027 1.142197 270)
			(unlocked yes)
			(layer "F.SilkS")
			(effects
				(font
					(size 0.635 0.635)
					(thickness 0.1778)
				)
			)
		)
		(property "Value" "1MM"
			(at -2.092783 1.790085 0)
			(unlocked yes)
			(layer "F.SilkS")
			(hide yes)
			(effects
				(font
					(size 0.635 0.635)
					(thickness 0.1778)
				)
			)
		)
		(sheetname "01-M2_NEO-M9N_MODULE")
		(sheetfile "01-M2_NEO-M9N_MODULE.kicad_sch")
		(duplicate_pad_numbers_are_jumpers no)
		(pad "1" smd circle
			(at 0 0 90)
			(size 1 1)
			(layers "F.Cu" "F.Mask" "F.Paste")
			(net "TX_GPS")
			(solder_paste_margin -100)
			(thermal_bridge_angle 90)
		)
	)
	(gr_line
		(start 137.501095 84.0036)
		(end 159.501095 84.0036)
		(stroke
			(width 0.05)
			(type solid)
		)
		(layer "Edge.Cuts")
	)
	(gr_line
		(start 137.501105 122.85359)
		(end 137.501095 84.0036)
		(stroke
			(width 0.05)
			(type solid)
		)
		(layer "Edge.Cuts")
	)
	(gr_line
		(start 138.0761 122.85359)
		(end 138.076105 122.85359)
		(stroke
			(width 0.05)
			(type solid)
		)
		(layer "Edge.Cuts")
	)
	(gr_arc
		(start 138.0761 122.85359)
		(mid 138.429662 123.000036)
		(end 138.576095 123.353595)
		(stroke
			(width 0.05)
			(type solid)
		)
		(layer "Edge.Cuts")
	)
	(gr_line
		(start 138.076105 122.85359)
		(end 137.501105 122.85359)
		(stroke
			(width 0.05)
			(type solid)
		)
		(layer "Edge.Cuts")
	)
	(gr_line
		(start 138.576105 126.0036)
		(end 138.576095 123.353595)
		(stroke
			(width 0.05)
			(type solid)
		)
		(layer "Edge.Cuts")
	)
	(gr_line
		(start 153.526105 123.1036)
		(end 153.526105 126.0036)
		(stroke
			(width 0.05)
			(type solid)
		)
		(layer "Edge.Cuts")
	)
	(gr_arc
		(start 153.526105 123.1036)
		(mid 154.126105 122.5036)
		(end 154.726105 123.1036)
		(stroke
			(width 0.05)
			(type solid)
		)
		(layer "Edge.Cuts")
	)
	(gr_line
		(start 153.526105 126.0036)
		(end 138.576105 126.0036)
		(stroke
			(width 0.05)
			(type solid)
		)
		(layer "Edge.Cuts")
	)
	(gr_line
		(start 154.726105 126.0036)
		(end 154.726105 123.1036)
		(stroke
			(width 0.05)
			(type solid)
		)
		(layer "Edge.Cuts")
	)
	(gr_line
		(start 158.426105 123.3536)
		(end 158.426105 126.0036)
		(stroke
			(width 0.05)
			(type solid)
		)
		(layer "Edge.Cuts")
	)
	(gr_arc
		(start 158.426105 123.3536)
		(mid 158.572555 123.000043)
		(end 158.926115 122.85359)
		(stroke
			(width 0.05)
			(type solid)
		)
		(layer "Edge.Cuts")
	)
	(gr_line
		(start 158.426105 126.0036)
		(end 154.726105 126.0036)
		(stroke
			(width 0.05)
			(type solid)
		)
		(layer "Edge.Cuts")
	)
	(gr_line
		(start 159.501095 84.0036)
		(end 159.501105 122.85359)
		(stroke
			(width 0.05)
			(type solid)
		)
		(layer "Edge.Cuts")
	)
	(gr_line
		(start 159.501105 122.85359)
		(end 158.926115 122.85359)
		(stroke
			(width 0.05)
			(type solid)
		)
		(layer "Edge.Cuts")
	)
	(segment
		(start 146.053395 113.21797)
		(end 146.053395 112.16356)
		(width 0.1905)
		(layer "F.Cu")
		(net "NetLED1_1")
	)
	(segment
		(start 146.039455 112.14962)
		(end 146.053395 112.16356)
		(width 0.1905)
		(layer "F.Cu")
		(net "NetLED1_1")
	)
	(segment
		(start 143.801105 110.98182)
		(end 143.868235 110.91469)
		(width 0.1905)
		(layer "F.Cu")
		(net "NetLED1_2")
	)
	(segment
		(start 143.868235 110.91469)
		(end 144.607415 110.91469)
		(width 0.1905)
		(layer "F.Cu")
		(net "NetLED1_2")
	)
	(segment
		(start 144.872475 110.64962)
		(end 146.039455 110.64962)
		(width 0.1905)
		(layer "F.Cu")
		(net "NetLED1_2")
	)
	(segment
		(start 144.607415 110.91469)
		(end 144.872475 110.64962)
		(width 0.1905)
		(layer "F.Cu")
		(net "NetLED1_2")
	)
	(segment
		(start 143.801105 111.2335)
		(end 143.801105 110.98182)
		(width 0.1905)
		(layer "F.Cu")
		(net "NetLED1_2")
	)
	(segment
		(start 141.701105 113.7036)
		(end 141.701105 113.1286)
		(width 0.1905)
		(layer "F.Cu")
		(net "NetJ1_46")
	)
	(segment
		(start 141.701105 113.7036)
		(end 142.501105 114.5036)
		(width 0.1905)
		(layer "F.Cu")
		(net "NetJ1_46")
	)
	(via
		(at 142.501105 114.5036)
		(size 0.4064)
		(drill 0.254)
		(layers "F.Cu" "B.Cu")
		(net "NetJ1_46")
	)
	(segment
		(start 144.969415 116.07191)
		(end 145.728625 116.83112)
		(width 0.1905)
		(layer "B.Cu")
		(net "NetJ1_46")
	)
	(segment
		(start 146.332105 123.13389)
		(end 146.332105 118.28805)
		(width 0.1905)
		(layer "B.Cu")
		(net "NetJ1_46")
	)
	(segment
		(start 146.507105 124.4786)
		(end 146.507105 123.57124)
		(width 0.1905)
		(layer "B.Cu")
		(net "NetJ1_46")
	)
	(segment
		(start 142.501105 114.5036)
		(end 143.185535 115.18803)
		(width 0.1905)
		(layer "B.Cu")
		(net "NetJ1_46")
	)
	(arc
		(start 146.376671 123.256344)
		(mid 146.473206 123.40082)
		(end 146.507105 123.57124)
		(width 0.1905)
		(layer "B.Cu")
		(net "NetJ1_46")
	)
	(arc
		(start 145.728622 116.831113)
		(mid 146.175265 117.499561)
		(end 146.332105 118.28805)
		(width 0.1905)
		(layer "B.Cu")
		(net "NetJ1_46")
	)
	(arc
		(start 146.376673 123.25634)
		(mid 146.343594 123.199044)
		(end 146.332105 123.13389)
		(width 0.1905)
		(layer "B.Cu")
		(net "NetJ1_46")
	)
	(arc
		(start 144.444952 115.709565)
		(mid 144.723607 115.86696)
		(end 144.969413 116.071902)
		(width 0.1905)
		(layer "B.Cu")
		(net "NetJ1_46")
	)
	(arc
		(start 143.716215 115.55281)
		(mid 144.088918 115.592442)
		(end 144.444952 115.709565)
		(width 0.1905)
		(layer "B.Cu")
		(net "NetJ1_46")
	)
	(arc
		(start 143.716208 115.552818)
		(mid 143.434115 115.394794)
		(end 143.185526 115.188029)
		(width 0.1905)
		(layer "B.Cu")
		(net "NetJ1_46")
	)
	(segment
		(start 140.601105 113.7036)
		(end 140.601105 113.1286)
		(width 0.1905)
		(layer "F.Cu")
		(net "NetJ1_35")
	)
	(segment
		(start 140.601105 113.7036)
		(end 141.501105 114.6036)
		(width 0.1905)
		(layer "F.Cu")
		(net "NetJ1_35")
	)
	(segment
		(start 149.251105 124.7286)
		(end 149.251105 121.42431)
		(width 0.1905)
		(layer "F.Cu")
		(net "NetJ1_35")
	)
	(via
		(at 141.501105 114.6036)
		(size 0.4064)
		(drill 0.254)
		(layers "F.Cu" "B.Cu")
		(net "NetJ1_35")
	)
	(via
		(at 149.301105 121.3036)
		(size 0.4064)
		(drill 0.254)
		(layers "F.Cu" "B.Cu")
		(net "NetJ1_35")
	)
	(arc
		(start 149.251105 121.42431)
		(mid 149.2641 121.358982)
		(end 149.301105 121.3036)
		(width 0.1905)
		(layer "F.Cu")
		(net "NetJ1_35")
	)
	(segment
		(start 147.428925 110.92788)
		(end 149.456195 110.92788)
		(width 0.1905)
		(layer "B.Cu")
		(net "NetJ1_35")
	)
	(segment
		(start 145.954505 111.39963)
		(end 145.954505 111.39962)
		(width 0.1905)
		(layer "B.Cu")
		(net "NetJ1_35")
	)
	(segment
		(start 143.318265 112.68644)
		(end 143.318475 112.68623)
		(width 0.1905)
		(layer "B.Cu")
		(net "NetJ1_35")
	)
	(segment
		(start 145.621885 111.73225)
		(end 145.954505 111.39963)
		(width 0.1905)
		(layer "B.Cu")
		(net "NetJ1_35")
	)
	(segment
		(start 141.571815 114.43289)
		(end 143.318265 112.68644)
		(width 0.1905)
		(layer "B.Cu")
		(net "NetJ1_35")
	)
	(segment
		(start 151.001105 119.58939)
		(end 151.001105 113.0557)
		(width 0.1905)
		(layer "B.Cu")
		(net "NetJ1_35")
	)
	(arc
		(start 150.496087 120.808622)
		(mid 149.947825 121.174959)
		(end 149.301105 121.3036)
		(width 0.1905)
		(layer "B.Cu")
		(net "NetJ1_35")
	)
	(arc
		(start 145.621879 111.732254)
		(mid 145.474173 111.86758)
		(end 145.315215 111.989493)
		(width 0.1905)
		(layer "B.Cu")
		(net "NetJ1_35")
	)
	(arc
		(start 149.456195 110.92789)
		(mid 149.889672 111.014114)
		(end 150.257156 111.259659)
		(width 0.1905)
		(layer "B.Cu")
		(net "NetJ1_35")
	)
	(arc
		(start 143.318478 112.686229)
		(mid 143.631694 112.47705)
		(end 144.001105 112.4036)
		(width 0.1905)
		(layer "B.Cu")
		(net "NetJ1_35")
	)
	(arc
		(start 145.954501 111.399626)
		(mid 146.654898 111.048689)
		(end 147.428925 110.92788)
		(width 0.1905)
		(layer "B.Cu")
		(net "NetJ1_35")
	)
	(arc
		(start 151.001105 119.58939)
		(mid 150.869854 120.249232)
		(end 150.496084 120.808619)
		(width 0.1905)
		(layer "B.Cu")
		(net "NetJ1_35")
	)
	(arc
		(start 145.315214 111.989493)
		(mid 144.690011 112.297624)
		(end 144.001105 112.4036)
		(width 0.1905)
		(layer "B.Cu")
		(net "NetJ1_35")
	)
	(arc
		(start 150.257156 111.259649)
		(mid 150.807759 112.083684)
		(end 151.001105 113.0557)
		(width 0.1905)
		(layer "B.Cu")
		(net "NetJ1_35")
	)
	(arc
		(start 141.501105 114.6036)
		(mid 141.519481 114.511216)
		(end 141.571812 114.432897)
		(width 0.1905)
		(layer "B.Cu")
		(net "NetJ1_35")
	)
	(segment
		(start 147.701105 112.3286)
		(end 147.701105 110.5036)
		(width 0.1905)
		(layer "F.Cu")
		(net "SDA")
	)
	(segment
		(start 146.901105 112.3286)
		(end 147.701105 112.3286)
		(width 0.1905)
		(layer "F.Cu")
		(net "SDA")
	)
	(segment
		(start 147.701105 110.5036)
		(end 148.801155 109.40355)
		(width 0.1905)
		(layer "F.Cu")
		(net "SDA")
	)
	(segment
		(start 148.801155 109.40355)
		(end 148.801155 108.20341)
		(width 0.1905)
		(layer "F.Cu")
		(net "SDA")
	)
	(via
		(at 146.901105 112.3286)
		(size 0.4064)
		(drill 0.254)
		(layers "F.Cu" "B.Cu")
		(net "SDA")
	)
	(segment
		(start 146.901105 119.0036)
		(end 147.507105 119.6096)
		(width 0.1905)
		(layer "B.Cu")
		(net "SDA")
	)
	(segment
		(start 146.901105 119.0036)
		(end 146.901105 112.3286)
		(width 0.1905)
		(layer "B.Cu")
		(net "SDA")
	)
	(segment
		(start 147.507105 124.4786)
		(end 147.507105 119.6096)
		(width 0.1905)
		(layer "B.Cu")
		(net "SDA")
	)
	(segment
		(start 149.201105 110.6036)
		(end 149.900975 109.90373)
		(width 0.1905)
		(layer "F.Cu")
		(net "SCL")
	)
	(segment
		(start 149.201105 112.3286)
		(end 149.201105 110.6036)
		(width 0.1905)
		(layer "F.Cu")
		(net "SCL")
	)
	(segment
		(start 149.900975 109.90373)
		(end 149.900975 108.20341)
		(width 0.1905)
		(layer "F.Cu")
		(net "SCL")
	)
	(segment
		(start 149.201105 112.3286)
		(end 150.001105 112.3286)
		(width 0.1905)
		(layer "F.Cu")
		(net "SCL")
	)
	(via
		(at 150.001105 112.3286)
		(size 0.4064)
		(drill 0.254)
		(layers "F.Cu" "B.Cu")
		(net "SCL")
	)
	(segment
		(start 148.007105 124.4786)
		(end 148.007105 121.6976)
		(width 0.1905)
		(layer "B.Cu")
		(net "SCL")
	)
	(segment
		(start 148.007105 121.6976)
		(end 150.001105 119.7036)
		(width 0.1905)
		(layer "B.Cu")
		(net "SCL")
	)
	(segment
		(start 150.001105 119.7036)
		(end 150.001105 112.3286)
		(width 0.1905)
		(layer "B.Cu")
		(net "SCL")
	)
	(segment
		(start 141.251105 120.6536)
		(end 141.301105 120.6036)
		(width 0.1905)
		(layer "F.Cu")
		(net "NetJ1_67")
	)
	(segment
		(start 141.251105 124.7286)
		(end 141.251105 120.6536)
		(width 0.1905)
		(layer "F.Cu")
		(net "NetJ1_67")
	)
	(segment
		(start 141.301105 120.6036)
		(end 141.301105 119.5286)
		(width 0.1905)
		(layer "F.Cu")
		(net "NetJ1_67")
	)
	(segment
		(start 145.501105 121.1036)
		(end 145.501105 119.5286)
		(width 0.1905)
		(layer "F.Cu")
		(net "NetJ1_50")
	)
	(via
		(at 145.501105 121.1036)
		(size 0.4064)
		(drill 0.254)
		(layers "F.Cu" "B.Cu")
		(net "NetJ1_50")
	)
	(segment
		(start 145.504105 124.4756)
		(end 145.507105 124.4786)
		(width 0.2032)
		(layer "B.Cu")
		(net "NetJ1_50")
	)
	(segment
		(start 145.501105 121.1036)
		(end 145.504105 121.1066)
		(width 0.2032)
		(layer "B.Cu")
		(net "NetJ1_50")
	)
	(segment
		(start 145.504105 124.4756)
		(end 145.504105 121.1066)
		(width 0.1905)
		(layer "B.Cu")
		(net "NetJ1_50")
	)
	(segment
		(start 151.601105 90.9036)
		(end 152.286785 90.9036)
		(width 0.254)
		(layer "F.Cu")
		(net "NetQ1_1")
	)
	(segment
		(start 151.136105 91.3186)
		(end 151.551105 90.9036)
		(width 0.254)
		(layer "F.Cu")
		(net "NetQ1_1")
	)
	(segment
		(start 153.501105 92.0036)
		(end 153.501105 90.0536)
		(width 0.254)
		(layer "F.Cu")
		(net "NetQ1_1")
	)
	(segment
		(start 152.286785 90.47867)
		(end 152.761855 90.0036)
		(width 0.254)
		(layer "F.Cu")
		(net "NetQ1_1")
	)
	(segment
		(start 149.631505 91.3186)
		(end 151.136105 91.3186)
		(width 0.254)
		(layer "F.Cu")
		(net "NetQ1_1")
	)
	(segment
		(start 151.551105 90.9036)
		(end 151.601105 90.9036)
		(width 0.254)
		(layer "F.Cu")
		(net "NetQ1_1")
	)
	(segment
		(start 152.761855 90.0036)
		(end 153.451105 90.0036)
		(width 0.254)
		(layer "F.Cu")
		(net "NetQ1_1")
	)
	(segment
		(start 153.451105 90.0036)
		(end 153.501105 90.0536)
		(width 0.254)
		(layer "F.Cu")
		(net "NetQ1_1")
	)
	(segment
		(start 152.286785 90.9036)
		(end 152.286785 90.47867)
		(width 0.254)
		(layer "F.Cu")
		(net "NetQ1_1")
	)
	(segment
		(start 153.501105 92.0036)
		(end 153.501105 92.0036)
		(width 0.254)
		(layer "F.Cu")
		(net "NetQ1_1")
	)
	(segment
		(start 147.580355 90.52435)
		(end 147.701105 90.4036)
		(width 0.1905)
		(layer "F.Cu")
		(net "NetQ1_3")
	)
	(segment
		(start 144.951105 91.6036)
		(end 145.701105 91.6036)
		(width 0.1905)
		(layer "F.Cu")
		(net "NetQ1_3")
	)
	(segment
		(start 145.701105 91.6036)
		(end 146.780355 90.52435)
		(width 0.1905)
		(layer "F.Cu")
		(net "NetQ1_3")
	)
	(segment
		(start 146.780355 90.52435)
		(end 147.580355 90.52435)
		(width 0.1905)
		(layer "F.Cu")
		(net "NetQ1_3")
	)
	(segment
		(start 148.301105 93.5036)
		(end 149.301105 93.5036)
		(width 0.1905)
		(layer "F.Cu")
		(net "VDD_USB")
	)
	(segment
		(start 148.201105 93.6036)
		(end 148.301105 93.5036)
		(width 0.1905)
		(layer "F.Cu")
		(net "VDD_USB")
	)
	(segment
		(start 149.301105 93.61492)
		(end 149.301105 93.5036)
		(width 0.1905)
		(layer "F.Cu")
		(net "VDD_USB")
	)
	(segment
		(start 148.801155 96.00379)
		(end 148.801155 94.11487)
		(width 0.1905)
		(layer "F.Cu")
		(net "VDD_USB")
	)
	(segment
		(start 148.801155 94.11487)
		(end 149.301105 93.61492)
		(width 0.1905)
		(layer "F.Cu")
		(net "VDD_USB")
	)
	(segment
		(start 150.180375 95.01313)
		(end 150.241335 94.95217)
		(width 0.2413)
		(layer "F.Cu")
		(net "USB_DP")
	)
	(segment
		(start 156.210655 124.63095)
		(end 156.210655 119.6036)
		(width 0.2413)
		(layer "F.Cu")
		(net "USB_DP")
	)
	(segment
		(start 156.210655 119.6036)
		(end 156.210655 119.6036)
		(width 0.2413)
		(layer "F.Cu")
		(net "USB_DP")
	)
	(segment
		(start 150.241335 94.95217)
		(end 150.241335 94.24192)
		(width 0.2413)
		(layer "F.Cu")
		(net "USB_DP")
	)
	(segment
		(start 150.180375 95.72439)
		(end 150.180375 95.01313)
		(width 0.2413)
		(layer "F.Cu")
		(net "USB_DP")
	)
	(segment
		(start 149.900975 96.00379)
		(end 150.180375 95.72439)
		(width 0.2413)
		(layer "F.Cu")
		(net "USB_DP")
	)
	(via
		(at 150.147685 94.1036)
		(size 0.4064)
		(drill 0.254)
		(layers "F.Cu" "B.Cu")
		(net "USB_DP")
	)
	(via
		(at 156.210655 119.6036)
		(size 0.4064)
		(drill 0.254)
		(layers "F.Cu" "B.Cu")
		(net "USB_DP")
	)
	(arc
		(start 156.251104 124.728601)
		(mid 156.221168 124.683798)
		(end 156.210656 124.63095)
		(width 0.2413)
		(layer "F.Cu")
		(net "USB_DP")
	)
	(segment
		(start 154.701105 120.8227)
		(end 155.260675 120.8227)
		(width 0.2413)
		(layer "B.Cu")
		(net "USB_DP")
	)
	(segment
		(start 152.847545 119.14274)
		(end 154.404755 120.69995)
		(width 0.2413)
		(layer "B.Cu")
		(net "USB_DP")
	)
	(segment
		(start 152.501105 118.30636)
		(end 152.501105 113.3484)
		(width 0.2413)
		(layer "B.Cu")
		(net "USB_DP")
	)
	(segment
		(start 150.179275 94.28415)
		(end 150.179275 94.17986)
		(width 0.2413)
		(layer "B.Cu")
		(net "USB_DP")
	)
	(segment
		(start 155.796745 120.60065)
		(end 155.798865 120.59854)
		(width 0.2413)
		(layer "B.Cu")
		(net "USB_DP")
	)
	(segment
		(start 156.210655 119.60439)
		(end 156.210655 119.6036)
		(width 0.2413)
		(layer "B.Cu")
		(net "USB_DP")
	)
	(segment
		(start 150.241335 108.81704)
		(end 150.241335 94.43397)
		(width 0.2413)
		(layer "B.Cu")
		(net "USB_DP")
	)
	(segment
		(start 151.103645 110.89883)
		(end 151.757155 111.55235)
		(width 0.2413)
		(layer "B.Cu")
		(net "USB_DP")
	)
	(arc
		(start 151.103642 110.898833)
		(mid 150.465441 109.943698)
		(end 150.241335 108.81704)
		(width 0.2413)
		(layer "B.Cu")
		(net "USB_DP")
	)
	(arc
		(start 150.147684 94.103591)
		(mid 150.171065 94.138584)
		(end 150.179276 94.17986)
		(width 0.2413)
		(layer "B.Cu")
		(net "USB_DP")
	)
	(arc
		(start 152.847542 119.142733)
		(mid 152.591141 118.759002)
		(end 152.501105 118.30636)
		(width 0.2413)
		(layer "B.Cu")
		(net "USB_DP")
	)
	(arc
		(start 156.210655 119.60439)
		(mid 156.103634 120.14242)
		(end 155.798865 120.59854)
		(width 0.2413)
		(layer "B.Cu")
		(net "USB_DP")
	)
	(arc
		(start 150.210303 94.359052)
		(mid 150.23327 94.393425)
		(end 150.241335 94.43397)
		(width 0.2413)
		(layer "B.Cu")
		(net "USB_DP")
	)
	(arc
		(start 150.210304 94.359061)
		(mid 150.187339 94.324692)
		(end 150.179275 94.28415)
		(width 0.2413)
		(layer "B.Cu")
		(net "USB_DP")
	)
	(arc
		(start 151.757156 111.552349)
		(mid 152.307759 112.376384)
		(end 152.501105 113.3484)
		(width 0.2413)
		(layer "B.Cu")
		(net "USB_DP")
	)
	(arc
		(start 154.701105 120.82271)
		(mid 154.54072 120.790807)
		(end 154.404753 120.699955)
		(width 0.2413)
		(layer "B.Cu")
		(net "USB_DP")
	)
	(arc
		(start 155.796747 120.600652)
		(mid 155.550795 120.764992)
		(end 155.260675 120.8227)
		(width 0.2413)
		(layer "B.Cu")
		(net "USB_DP")
	)
	(segment
		(start 150.660435 94.95217)
		(end 150.660435 94.24192)
		(width 0.2413)
		(layer "F.Cu")
		(net "USB_DM")
	)
	(segment
		(start 155.604255 119.6036)
		(end 155.686805 119.68615)
		(width 0.2413)
		(layer "F.Cu")
		(net "USB_DM")
	)
	(segment
		(start 150.660435 94.95217)
		(end 150.721395 95.01313)
		(width 0.2413)
		(layer "F.Cu")
		(net "USB_DM")
	)
	(segment
		(start 155.791555 124.63095)
		(end 155.791555 119.92533)
		(width 0.2413)
		(layer "F.Cu")
		(net "USB_DM")
	)
	(segment
		(start 155.686805 119.82058)
		(end 155.791555 119.92533)
		(width 0.2413)
		(layer "F.Cu")
		(net "USB_DM")
	)
	(segment
		(start 155.686805 119.82058)
		(end 155.686805 119.68615)
		(width 0.2413)
		(layer "F.Cu")
		(net "USB_DM")
	)
	(segment
		(start 150.721395 95.72439)
		(end 151.000795 96.00379)
		(width 0.2413)
		(layer "F.Cu")
		(net "USB_DM")
	)
	(segment
		(start 150.721395 95.72439)
		(end 150.721395 95.01313)
		(width 0.2413)
		(layer "F.Cu")
		(net "USB_DM")
	)
	(via
		(at 155.604255 119.6036)
		(size 0.4064)
		(drill 0.254)
		(layers "F.Cu" "B.Cu")
		(net "USB_DM")
	)
	(via
		(at 150.754085 94.1036)
		(size 0.4064)
		(drill 0.254)
		(layers "F.Cu" "B.Cu")
		(net "USB_DM")
	)
	(arc
		(start 155.791555 124.63095)
		(mid 155.781043 124.683799)
		(end 155.751106 124.728601)
		(width 0.2413)
		(layer "F.Cu")
		(net "USB_DM")
	)
	(segment
		(start 153.145845 118.84834)
		(end 154.453615 120.15611)
		(width 0.2413)
		(layer "B.Cu")
		(net "USB_DM")
	)
	(segment
		(start 150.660435 106.24761)
		(end 150.981415 106.24761)
		(width 0.2413)
		(layer "B.Cu")
		(net "USB_DM")
	)
	(segment
		(start 155.604255 120.05456)
		(end 155.604255 119.6036)
		(width 0.2413)
		(layer "B.Cu")
		(net "USB_DM")
	)
	(segment
		(start 150.981415 106.24761)
		(end 150.981415 105.75231)
		(width 0.2413)
		(layer "B.Cu")
		(net "USB_DM")
	)
	(segment
		(start 150.660435 105.75231)
		(end 150.981415 105.75231)
		(width 0.2413)
		(layer "B.Cu")
		(net "USB_DM")
	)
	(segment
		(start 150.981415 105.25701)
		(end 150.981415 104.76171)
		(width 0.2413)
		(layer "B.Cu")
		(net "USB_DM")
	)
	(segment
		(start 155.051105 120.4036)
		(end 155.259685 120.4036)
		(width 0.2413)
		(layer "B.Cu")
		(net "USB_DM")
	)
	(segment
		(start 151.401105 110.6036)
		(end 152.055565 111.25806)
		(width 0.2413)
		(layer "B.Cu")
		(net "USB_DM")
	)
	(segment
		(start 150.660435 100.3036)
		(end 150.660435 94.43397)
		(width 0.2413)
		(layer "B.Cu")
		(net "USB_DM")
	)
	(segment
		(start 150.660435 106.86358)
		(end 150.660435 106.24761)
		(width 0.2413)
		(layer "B.Cu")
		(net "USB_DM")
	)
	(segment
		(start 150.660435 103.77111)
		(end 150.660435 100.3036)
		(width 0.2413)
		(layer "B.Cu")
		(net "USB_DM")
	)
	(segment
		(start 152.920205 118.3036)
		(end 152.920205 113.34549)
		(width 0.2413)
		(layer "B.Cu")
		(net "USB_DM")
	)
	(segment
		(start 150.660435 105.75231)
		(end 150.660435 105.25701)
		(width 0.2413)
		(layer "B.Cu")
		(net "USB_DM")
	)
	(segment
		(start 150.690955 104.26641)
		(end 150.690955 103.77111)
		(width 0.2413)
		(layer "B.Cu")
		(net "USB_DM")
	)
	(segment
		(start 150.722495 94.28415)
		(end 150.722495 94.17986)
		(width 0.2413)
		(layer "B.Cu")
		(net "USB_DM")
	)
	(segment
		(start 150.660435 103.77111)
		(end 150.690955 103.77111)
		(width 0.2413)
		(layer "B.Cu")
		(net "USB_DM")
	)
	(segment
		(start 150.660435 104.26641)
		(end 150.690955 104.26641)
		(width 0.2413)
		(layer "B.Cu")
		(net "USB_DM")
	)
	(segment
		(start 150.660435 105.25701)
		(end 150.981415 105.25701)
		(width 0.2413)
		(layer "B.Cu")
		(net "USB_DM")
	)
	(segment
		(start 150.660435 104.76171)
		(end 150.660435 104.26641)
		(width 0.2413)
		(layer "B.Cu")
		(net "USB_DM")
	)
	(segment
		(start 150.660435 104.76171)
		(end 150.981415 104.76171)
		(width 0.2413)
		(layer "B.Cu")
		(net "USB_DM")
	)
	(segment
		(start 150.660435 108.81547)
		(end 150.660435 106.86358)
		(width 0.2413)
		(layer "B.Cu")
		(net "USB_DM")
	)
	(arc
		(start 155.604255 120.05456)
		(mid 155.577446 120.189337)
		(end 155.501101 120.303596)
		(width 0.2413)
		(layer "B.Cu")
		(net "USB_DM")
	)
	(arc
		(start 150.660435 94.43397)
		(mid 150.6685 94.393425)
		(end 150.691467 94.359052)
		(width 0.2413)
		(layer "B.Cu")
		(net "USB_DM")
	)
	(arc
		(start 151.401103 110.603602)
		(mid 150.852928 109.7832)
		(end 150.660434 108.81547)
		(width 0.2413)
		(layer "B.Cu")
		(net "USB_DM")
	)
	(arc
		(start 150.722495 94.17986)
		(mid 150.730705 94.138584)
		(end 150.754086 94.103591)
		(width 0.2413)
		(layer "B.Cu")
		(net "USB_DM")
	)
	(arc
		(start 155.051105 120.4036)
		(mid 154.727749 120.33928)
		(end 154.45362 120.156114)
		(width 0.2413)
		(layer "B.Cu")
		(net "USB_DM")
	)
	(arc
		(start 152.055567 111.258068)
		(mid 152.695493 112.215785)
		(end 152.920206 113.34549)
		(width 0.2413)
		(layer "B.Cu")
		(net "USB_DM")
	)
	(arc
		(start 150.722495 94.28415)
		(mid 150.714431 94.324691)
		(end 150.691466 94.359061)
		(width 0.2413)
		(layer "B.Cu")
		(net "USB_DM")
	)
	(arc
		(start 153.145844 118.848341)
		(mid 152.978847 118.598412)
		(end 152.920205 118.3036)
		(width 0.2413)
		(layer "B.Cu")
		(net "USB_DM")
	)
	(arc
		(start 155.501105 120.3036)
		(mid 155.390341 120.37761)
		(end 155.259685 120.403599)
		(width 0.2413)
		(layer "B.Cu")
		(net "USB_DM")
	)
	(segment
		(start 149.701105 114.7036)
		(end 150.701105 113.7036)
		(width 0.1905)
		(layer "F.Cu")
		(net "TX_GPS")
	)
	(segment
		(start 150.701105 113.7036)
		(end 150.701105 110.6036)
		(width 0.1905)
		(layer "F.Cu")
		(net "TX_GPS")
	)
	(segment
		(start 142.701105 118.6036)
		(end 142.701105 115.7036)
		(width 0.1905)
		(layer "F.Cu")
		(net "TX_GPS")
	)
	(segment
		(start 142.701105 115.7036)
		(end 143.701105 114.7036)
		(width 0.1905)
		(layer "F.Cu")
		(net "TX_GPS")
	)
	(segment
		(start 150.701105 110.6036)
		(end 150.701105 110.38455)
		(width 0.1905)
		(layer "F.Cu")
		(net "TX_GPS")
	)
	(segment
		(start 151.000795 110.08486)
		(end 151.000795 108.20341)
		(width 0.1905)
		(layer "F.Cu")
		(net "TX_GPS")
	)
	(segment
		(start 143.701105 114.7036)
		(end 149.701105 114.7036)
		(width 0.1905)
		(layer "F.Cu")
		(net "TX_GPS")
	)
	(segment
		(start 150.701105 110.38455)
		(end 151.000795 110.08486)
		(width 0.1905)
		(layer "F.Cu")
		(net "TX_GPS")
	)
	(segment
		(start 142.701105 120.4036)
		(end 142.701105 119.6036)
		(width 0.1905)
		(layer "F.Cu")
		(net "TX_GPS_CONN")
	)
	(segment
		(start 142.001105 121.1036)
		(end 142.701105 120.4036)
		(width 0.1905)
		(layer "F.Cu")
		(net "TX_GPS_CONN")
	)
	(via
		(at 142.001105 121.1036)
		(size 0.4064)
		(drill 0.254)
		(layers "F.Cu" "B.Cu")
		(net "TX_GPS_CONN")
	)
	(segment
		(start 142.004105 124.4756)
		(end 142.004105 121.1066)
		(width 0.1905)
		(layer "B.Cu")
		(net "TX_GPS_CONN")
	)
	(segment
		(start 142.004105 124.4756)
		(end 142.007105 124.4786)
		(width 0.2032)
		(layer "B.Cu")
		(net "TX_GPS_CONN")
	)
	(segment
		(start 142.001105 121.1036)
		(end 142.004105 121.1066)
		(width 0.2032)
		(layer "B.Cu")
		(net "TX_GPS_CONN")
	)
	(segment
		(start 143.151105 112.7737)
		(end 143.151105 112.35964)
		(width 0.1905)
		(layer "F.Cu")
		(net "TP1")
	)
	(segment
		(start 143.070065 112.2786)
		(end 143.151105 112.35964)
		(width 0.1905)
		(layer "F.Cu")
		(net "TP1")
	)
	(segment
		(start 141.701105 112.2786)
		(end 143.070065 112.2786)
		(width 0.1905)
		(layer "F.Cu")
		(net "TP1")
	)
	(segment
		(start 153.200435 94.00427)
		(end 153.401105 93.8036)
		(width 0.254)
		(layer "F.Cu")
		(net "TP1")
	)
	(segment
		(start 140.601105 112.2786)
		(end 140.601105 112.08644)
		(width 0.1905)
		(layer "F.Cu")
		(net "TP1")
	)
	(segment
		(start 140.601105 112.2786)
		(end 141.701105 112.2786)
		(width 0.1905)
		(layer "F.Cu")
		(net "TP1")
	)
	(segment
		(start 153.200435 96.00379)
		(end 153.200435 94.00427)
		(width 0.254)
		(layer "F.Cu")
		(net "TP1")
	)
	(segment
		(start 140.801105 111.6036)
		(end 140.888975 111.51573)
		(width 0.1905)
		(layer "F.Cu")
		(net "TP1")
	)
	(via
		(at 141.401105 111.3036)
		(size 0.4064)
		(drill 0.254)
		(layers "F.Cu" "B.Cu")
		(net "TP1")
	)
	(via
		(at 153.401105 93.8036)
		(size 0.4064)
		(drill 0.254)
		(layers "F.Cu" "B.Cu")
		(net "TP1")
	)
	(arc
		(start 140.888976 111.515721)
		(mid 141.123943 111.358721)
		(end 141.401105 111.30359)
		(width 0.1905)
		(layer "F.Cu")
		(net "TP1")
	)
	(arc
		(start 140.601105 112.08644)
		(mid 140.653083 111.825128)
		(end 140.801104 111.603599)
		(width 0.1905)
		(layer "F.Cu")
		(net "TP1")
	)
	(segment
		(start 153.245055 93.64755)
		(end 153.401105 93.8036)
		(width 0.1905)
		(layer "B.Cu")
		(net "TP1")
	)
	(segment
		(start 151.140425 92.9036)
		(end 151.449005 92.9036)
		(width 0.1905)
		(layer "B.Cu")
		(net "TP1")
	)
	(segment
		(start 144.045055 110.55965)
		(end 148.057155 106.54755)
		(width 0.1905)
		(layer "B.Cu")
		(net "TP1")
	)
	(segment
		(start 148.801105 104.7515)
		(end 148.801105 94.95911)
		(width 0.1905)
		(layer "B.Cu")
		(net "TP1")
	)
	(segment
		(start 141.401105 111.3036)
		(end 142.249005 111.3036)
		(width 0.1905)
		(layer "B.Cu")
		(net "TP1")
	)
	(arc
		(start 149.344374 93.647549)
		(mid 150.168409 93.096946)
		(end 151.140425 92.9036)
		(width 0.1905)
		(layer "B.Cu")
		(net "TP1")
	)
	(arc
		(start 151.449005 92.9036)
		(mid 152.421021 93.096946)
		(end 153.245056 93.647549)
		(width 0.1905)
		(layer "B.Cu")
		(net "TP1")
	)
	(arc
		(start 148.73228 105.338775)
		(mid 148.478669 105.990051)
		(end 148.057156 106.547551)
		(width 0.1905)
		(layer "B.Cu")
		(net "TP1")
	)
	(arc
		(start 144.045056 110.559651)
		(mid 143.221021 111.110254)
		(end 142.249005 111.3036)
		(width 0.1905)
		(layer "B.Cu")
		(net "TP1")
	)
	(arc
		(start 148.801105 94.95911)
		(mid 148.942296 94.249297)
		(end 149.344372 93.647547)
		(width 0.1905)
		(layer "B.Cu")
		(net "TP1")
	)
	(arc
		(start 148.801105 104.7515)
		(mid 148.78384 105.047147)
		(end 148.73228 105.338775)
		(width 0.1905)
		(layer "B.Cu")
		(net "TP1")
	)
	(segment
		(start 155.400075 96.00379)
		(end 155.500265 95.9036)
		(width 0.254)
		(layer "F.Cu")
		(net "SAFEBOOT_N")
	)
	(segment
		(start 155.500265 95.9036)
		(end 157.601105 95.9036)
		(width 0.254)
		(layer "F.Cu")
		(net "SAFEBOOT_N")
	)
	(segment
		(start 152.001105 110.71482)
		(end 152.001105 110.6036)
		(width 0.1905)
		(layer "F.Cu")
		(net "RX_GPS")
	)
	(segment
		(start 150.044715 119.35999)
		(end 151.301105 118.1036)
		(width 0.1905)
		(layer "F.Cu")
		(net "RX_GPS")
	)
	(segment
		(start 144.701105 116.2036)
		(end 145.749525 116.2036)
		(width 0.1905)
		(layer "F.Cu")
		(net "RX_GPS")
	)
	(segment
		(start 144.101105 118.6036)
		(end 144.101105 116.8036)
		(width 0.1905)
		(layer "F.Cu")
		(net "RX_GPS")
	)
	(segment
		(start 151.301105 111.41482)
		(end 152.001105 110.71482)
		(width 0.1905)
		(layer "F.Cu")
		(net "RX_GPS")
	)
	(segment
		(start 144.101105 116.8036)
		(end 144.701105 116.2036)
		(width 0.1905)
		(layer "F.Cu")
		(net "RX_GPS")
	)
	(segment
		(start 148.905905 119.35999)
		(end 150.044715 119.35999)
		(width 0.1905)
		(layer "F.Cu")
		(net "RX_GPS")
	)
	(segment
		(start 152.001105 110.6036)
		(end 152.001105 108.30292)
		(width 0.1905)
		(layer "F.Cu")
		(net "RX_GPS")
	)
	(segment
		(start 145.749525 116.2036)
		(end 148.905905 119.35999)
		(width 0.1905)
		(layer "F.Cu")
		(net "RX_GPS")
	)
	(segment
		(start 152.001105 108.30292)
		(end 152.100615 108.20341)
		(width 0.1905)
		(layer "F.Cu")
		(net "RX_GPS")
	)
	(segment
		(start 151.301105 118.1036)
		(end 151.301105 111.41482)
		(width 0.1905)
		(layer "F.Cu")
		(net "RX_GPS")
	)
	(segment
		(start 144.101105 120.5036)
		(end 144.101105 119.6036)
		(width 0.1905)
		(layer "F.Cu")
		(net "RX_GPS_CONN")
	)
	(segment
		(start 143.101105 121.5036)
		(end 144.101105 120.5036)
		(width 0.1905)
		(layer "F.Cu")
		(net "RX_GPS_CONN")
	)
	(via
		(at 143.101105 121.5036)
		(size 0.4064)
		(drill 0.254)
		(layers "F.Cu" "B.Cu")
		(net "RX_GPS_CONN")
	)
	(segment
		(start 142.507105 124.4786)
		(end 142.507105 122.0976)
		(width 0.1905)
		(layer "B.Cu")
		(net "RX_GPS_CONN")
	)
	(segment
		(start 142.507105 122.0976)
		(end 143.101105 121.5036)
		(width 0.1905)
		(layer "B.Cu")
		(net "RX_GPS_CONN")
	)
	(segment
		(start 145.801105 94.3036)
		(end 145.801415 94.30391)
		(width 0.254)
		(layer "F.Cu")
		(net "RST_GPS")
	)
	(segment
		(start 141.301105 118.6786)
		(end 141.301105 117.6036)
		(width 0.254)
		(layer "F.Cu")
		(net "RST_GPS")
	)
	(segment
		(start 145.501105 118.6786)
		(end 145.501105 117.6036)
		(width 0.254)
		(layer "F.Cu")
		(net "RST_GPS")
	)
	(segment
		(start 145.301105 117.4036)
		(end 145.501105 117.6036)
		(width 0.254)
		(layer "F.Cu")
		(net "RST_GPS")
	)
	(segment
		(start 145.801415 96.00379)
		(end 145.801415 94.30391)
		(width 0.254)
		(layer "F.Cu")
		(net "RST_GPS")
	)
	(via
		(at 145.801105 94.3036)
		(size 0.4064)
		(drill 0.254)
		(layers "F.Cu" "B.Cu")
		(net "RST_GPS")
	)
	(via
		(at 141.301105 117.6036)
		(size 0.4064)
		(drill 0.254)
		(layers "F.Cu" "B.Cu")
		(net "RST_GPS")
	)
	(via
		(at 145.301105 117.4036)
		(size 0.4064)
		(drill 0.254)
		(layers "F.Cu" "B.Cu")
		(net "RST_GPS")
	)
	(segment
		(start 141.542345 117.4036)
		(end 145.301105 117.4036)
		(width 0.254)
		(layer "B.Cu")
		(net "RST_GPS")
	)
	(segment
		(start 141.342345 117.6036)
		(end 141.542345 117.4036)
		(width 0.254)
		(layer "B.Cu")
		(net "RST_GPS")
	)
	(segment
		(start 145.801105 96.4036)
		(end 145.801105 94.3036)
		(width 0.254)
		(layer "B.Cu")
		(net "RST_GPS")
	)
	(segment
		(start 141.201105 117.6036)
		(end 141.301105 117.6036)
		(width 0.254)
		(layer "B.Cu")
		(net "RST_GPS")
	)
	(segment
		(start 140.701105 101.5036)
		(end 145.801105 96.4036)
		(width 0.254)
		(layer "B.Cu")
		(net "RST_GPS")
	)
	(segment
		(start 140.701105 117.1036)
		(end 141.201105 117.6036)
		(width 0.254)
		(layer "B.Cu")
		(net "RST_GPS")
	)
	(segment
		(start 141.301105 117.6036)
		(end 141.342345 117.6036)
		(width 0.254)
		(layer "B.Cu")
		(net "RST_GPS")
	)
	(segment
		(start 140.701105 117.1036)
		(end 140.701105 101.5036)
		(width 0.254)
		(layer "B.Cu")
		(net "RST_GPS")
	)
	(segment
		(start 142.501955 96.00379)
		(end 142.501955 95.01276)
		(width 0.1905)
		(layer "F.Cu")
		(net "RF_MODULE")
	)
	(segment
		(start 141.401105 92.35507)
		(end 141.401105 92.2036)
		(width 0.1905)
		(layer "F.Cu")
		(net "RF_MODULE")
	)
	(arc
		(start 142.001106 93.803599)
		(mid 141.557041 93.139008)
		(end 141.401106 92.35507)
		(width 0.1905)
		(layer "F.Cu")
		(net "RF_MODULE")
	)
	(arc
		(start 142.001105 93.8036)
		(mid 142.371789 94.358367)
		(end 142.501955 95.01276)
		(width 0.1905)
		(layer "F.Cu")
		(net "RF_MODULE")
	)
	(segment
		(start 140.901105 88.7965)
		(end 140.901105 87.6286)
		(width 0.1905)
		(layer "F.Cu")
		(net "RF_ANT")
	)
	(segment
		(start 141.401105 90.0036)
		(end 141.401105 90.0036)
		(width 0.1905)
		(layer "F.Cu")
		(net "RF_ANT")
	)
	(segment
		(start 141.401105 91.2036)
		(end 141.401105 90.0036)
		(width 0.1905)
		(layer "F.Cu")
		(net "RF_ANT")
	)
	(arc
		(start 141.401103 90.003602)
		(mid 141.03105 89.449779)
		(end 140.901105 88.7965)
		(width 0.1905)
		(layer "F.Cu")
		(net "RF_ANT")
	)
	(segment
		(start 150.001105 116.60005)
		(end 150.001105 115.4036)
		(width 0.1905)
		(layer "F.Cu")
		(net "NetLED2_2")
	)
	(arc
		(start 150.251104 117.203601)
		(mid 150.066078 116.926689)
		(end 150.001105 116.60005)
		(width 0.1905)
		(layer "F.Cu")
		(net "NetLED2_2")
	)
	(segment
		(start 143.501105 91.48289)
		(end 143.501105 90.0036)
		(width 0.1905)
		(layer "F.Cu")
		(net "NetC5_2")
	)
	(segment
		(start 142.201105 90.0036)
		(end 143.501105 90.0036)
		(width 0.1905)
		(layer "F.Cu")
		(net "NetC5_2")
	)
	(arc
		(start 143.501105 91.48289)
		(mid 143.48811 91.548218)
		(end 143.451105 91.6036)
		(width 0.1905)
		(layer "F.Cu")
		(net "NetC5_2")
	)
	(segment
		(start 142.501105 109.9036)
		(end 142.501955 109.90275)
		(width 0.254)
		(layer "F.Cu")
		(net "LNA_EN")
	)
	(segment
		(start 142.501955 109.90275)
		(end 142.501955 108.20341)
		(width 0.254)
		(layer "F.Cu")
		(net "LNA_EN")
	)
	(segment
		(start 154.501105 90.0036)
		(end 154.501105 88.5036)
		(width 0.254)
		(layer "F.Cu")
		(net "LNA_EN")
	)
	(segment
		(start 154.501105 88.5036)
		(end 155.601105 88.5036)
		(width 0.254)
		(layer "F.Cu")
		(net "LNA_EN")
	)
	(via
		(at 142.501105 109.9036)
		(size 0.4064)
		(drill 0.254)
		(layers "F.Cu" "B.Cu")
		(net "LNA_EN")
	)
	(via
		(at 155.601105 88.5036)
		(size 0.4064)
		(drill 0.254)
		(layers "F.Cu" "B.Cu")
		(net "LNA_EN")
	)
	(segment
		(start 147.701105 93.4036)
		(end 150.501105 90.6036)
		(width 0.254)
		(layer "B.Cu")
		(net "LNA_EN")
	)
	(segment
		(start 142.501105 104.5036)
		(end 147.701105 99.3036)
		(width 0.254)
		(layer "B.Cu")
		(net "LNA_EN")
	)
	(segment
		(start 147.701105 99.3036)
		(end 147.701105 93.4036)
		(width 0.254)
		(layer "B.Cu")
		(net "LNA_EN")
	)
	(segment
		(start 153.501105 90.6036)
		(end 155.601105 88.5036)
		(width 0.254)
		(layer "B.Cu")
		(net "LNA_EN")
	)
	(segment
		(start 150.501105 90.6036)
		(end 153.501105 90.6036)
		(width 0.254)
		(layer "B.Cu")
		(net "LNA_EN")
	)
	(segment
		(start 142.501105 109.9036)
		(end 142.501105 104.5036)
		(width 0.254)
		(layer "B.Cu")
		(net "LNA_EN")
	)
	(segment
		(start 144.451105 113.89598)
		(end 144.451105 112.7737)
		(width 0.254)
		(layer "F.Cu")
		(net "GND")
	)
	(segment
		(start 147.001105 93.6036)
		(end 147.001105 93.6036)
		(width 0.254)
		(layer "F.Cu")
		(net "GND")
	)
	(segment
		(start 155.251105 124.7286)
		(end 155.251105 121.79484)
		(width 0.254)
		(layer "F.Cu")
		(net "GND")
	)
	(segment
		(start 144.501105 90.0036)
		(end 145.401105 90.0036)
		(width 0.254)
		(layer "F.Cu")
		(net "GND")
	)
	(segment
		(start 148.601105 122.54484)
		(end 148.601105 122.5036)
		(width 0.254)
		(layer "F.Cu")
		(net "GND")
	)
	(segment
		(start 149.751105 124.7286)
		(end 149.751105 122.5536)
		(width 0.254)
		(layer "F.Cu")
		(net "GND")
	)
	(segment
		(start 154.501105 92.0036)
		(end 155.201105 92.0036)
		(width 0.254)
		(layer "F.Cu")
		(net "GND")
	)
	(segment
		(start 140.251105 124.7286)
		(end 140.251105 123.1036)
		(width 0.254)
		(layer "F.Cu")
		(net "GND")
	)
	(segment
		(start 145.251105 124.7286)
		(end 145.251105 122.6036)
		(width 0.254)
		(layer "F.Cu")
		(net "GND")
	)
	(segment
		(start 146.751105 122.6536)
		(end 146.801105 122.6036)
		(width 0.254)
		(layer "F.Cu")
		(net "GND")
	)
	(segment
		(start 156.751105 124.7286)
		(end 156.751105 123.26574)
		(width 0.254)
		(layer "F.Cu")
		(net "GND")
	)
	(segment
		(start 152.701105 122.4036)
		(end 152.751105 122.4536)
		(width 0.254)
		(layer "F.Cu")
		(net "GND")
	)
	(segment
		(start 151.251105 124.7286)
		(end 151.251105 122.4536)
		(width 0.254)
		(layer "F.Cu")
		(net "GND")
	)
	(segment
		(start 143.751105 124.7286)
		(end 143.751105 123.4148)
		(width 0.254)
		(layer "F.Cu")
		(net "GND")
	)
	(segment
		(start 146.751105 124.7286)
		(end 146.751105 122.6536)
		(width 0.254)
		(layer "F.Cu")
		(net "GND")
	)
	(segment
		(start 156.501105 91.5036)
		(end 156.501105 90.6036)
		(width 0.254)
		(layer "F.Cu")
		(net "GND")
	)
	(segment
		(start 139.751105 124.7286)
		(end 139.751105 123.1036)
		(width 0.254)
		(layer "F.Cu")
		(net "GND")
	)
	(segment
		(start 151.201105 122.4036)
		(end 151.251105 122.4536)
		(width 0.254)
		(layer "F.Cu")
		(net "GND")
	)
	(segment
		(start 147.001105 93.6036)
		(end 147.001105 92.6036)
		(width 0.254)
		(layer "F.Cu")
		(net "GND")
	)
	(segment
		(start 155.101105 121.64484)
		(end 155.251105 121.79484)
		(width 0.254)
		(layer "F.Cu")
		(net "GND")
	)
	(segment
		(start 140.201105 124.7286)
		(end 140.251105 124.7286)
		(width 0.254)
		(layer "F.Cu")
		(net "GND")
	)
	(segment
		(start 156.751105 123.26574)
		(end 156.801105 123.21574)
		(width 0.254)
		(layer "F.Cu")
		(net "GND")
	)
	(segment
		(start 149.751105 122.5536)
		(end 149.801105 122.5036)
		(width 0.254)
		(layer "F.Cu")
		(net "GND")
	)
	(segment
		(start 144.447955 113.89913)
		(end 144.451105 113.89598)
		(width 0.254)
		(layer "F.Cu")
		(net "GND")
	)
	(segment
		(start 157.251105 124.7286)
		(end 157.251105 122.7036)
		(width 0.254)
		(layer "F.Cu")
		(net "GND")
	)
	(segment
		(start 155.101105 121.64484)
		(end 155.101105 121.6036)
		(width 0.254)
		(layer "F.Cu")
		(net "GND")
	)
	(segment
		(start 156.801105 123.21574)
		(end 156.801105 122.3036)
		(width 0.254)
		(layer "F.Cu")
		(net "GND")
	)
	(segment
		(start 148.101105 115.4036)
		(end 149.001105 115.4036)
		(width 0.254)
		(layer "F.Cu")
		(net "GND")
	)
	(segment
		(start 148.251105 122.89484)
		(end 148.601105 122.54484)
		(width 0.254)
		(layer "F.Cu")
		(net "GND")
	)
	(segment
		(start 139.251105 124.7286)
		(end 139.251105 123.3036)
		(width 0.254)
		(layer "F.Cu")
		(net "GND")
	)
	(segment
		(start 152.751105 124.7286)
		(end 152.751105 122.4536)
		(width 0.254)
		(layer "F.Cu")
		(net "GND")
	)
	(segment
		(start 143.751105 123.4148)
		(end 143.801105 123.3648)
		(width 0.254)
		(layer "F.Cu")
		(net "GND")
	)
	(segment
		(start 148.251105 124.7286)
		(end 148.251105 122.89484)
		(width 0.254)
		(layer "F.Cu")
		(net "GND")
	)
	(segment
		(start 143.801105 123.3648)
		(end 143.801105 122.2036)
		(width 0.254)
		(layer "F.Cu")
		(net "GND")
	)
	(via
		(at 142.223885 92.79785)
		(size 0.4064)
		(drill 0.254)
		(layers "F.Cu" "B.Cu")
		(net "GND")
	)
	(via
		(at 139.053105 91.0776)
		(size 0.4064)
		(drill 0.254)
		(layers "F.Cu" "B.Cu")
		(net "GND")
	)
	(via
		(at 139.434105 99.4596)
		(size 0.4064)
		(drill 0.254)
		(layers "F.Cu" "B.Cu")
		(net "GND")
	)
	(via
		(at 138.672105 119.2716)
		(size 0.4064)
		(drill 0.254)
		(layers "F.Cu" "B.Cu")
		(net "GND")
	)
	(via
		(at 139.434105 90.3156)
		(size 0.4064)
		(drill 0.254)
		(layers "F.Cu" "B.Cu")
		(net "GND")
	)
	(via
		(at 140.577105 97.1736)
		(size 0.4064)
		(drill 0.254)
		(layers "F.Cu" "B.Cu")
		(net "GND")
	)
	(via
		(at 139.053105 115.4616)
		(size 0.4064)
		(drill 0.254)
		(layers "F.Cu" "B.Cu")
		(net "GND")
	)
	(via
		(at 138.183655 120.97242)
		(size 0.4064)
		(drill 0.254)
		(layers "F.Cu" "B.Cu")
		(net "GND")
	)
	(via
		(at 145.530105 97.9356)
		(size 0.4064)
		(drill 0.254)
		(layers "F.Cu" "B.Cu")
		(net "GND")
	)
	(via
		(at 139.815105 97.1736)
		(size 0.4064)
		(drill 0.254)
		(layers "F.Cu" "B.Cu")
		(net "GND")
	)
	(via
		(at 155.101105 121.6036)
		(size 0.4064)
		(drill 0.254)
		(layers "F.Cu" "B.Cu")
		(net "GND")
	)
	(via
		(at 146.292105 88.7916)
		(size 0.4064)
		(drill 0.254)
		(layers "F.Cu" "B.Cu")
		(net "GND")
	)
	(via
		(at 140.306545 88.8121)
		(size 0.4064)
		(drill 0.254)
		(layers "F.Cu" "B.Cu")
		(net "GND")
	)
	(via
		(at 143.625105 92.6016)
		(size 0.4064)
		(drill 0.254)
		(layers "F.Cu" "B.Cu")
		(net "GND")
	)
	(via
		(at 140.415645 89.42358)
		(size 0.4064)
		(drill 0.254)
		(layers "F.Cu" "B.Cu")
		(net "GND")
	)
	(via
		(at 147.054105 88.7916)
		(size 0.4064)
		(drill 0.254)
		(layers "F.Cu" "B.Cu")
		(net "GND")
	)
	(via
		(at 142.189845 92.18024)
		(size 0.4064)
		(drill 0.254)
		(layers "F.Cu" "B.Cu")
		(net "GND")
	)
	(via
		(at 139.053105 88.0296)
		(size 0.4064)
		(drill 0.254)
		(layers "F.Cu" "B.Cu")
		(net "GND")
	)
	(via
		(at 151.626105 87.2676)
		(size 0.4064)
		(drill 0.254)
		(layers "F.Cu" "B.Cu")
		(net "GND")
	)
	(via
		(at 146.292105 91.8396)
		(size 0.4064)
		(drill 0.254)
		(layers "F.Cu" "B.Cu")
		(net "GND")
	)
	(via
		(at 155.055105 86.5056)
		(size 0.4064)
		(drill 0.254)
		(layers "F.Cu" "B.Cu")
		(net "GND")
	)
	(via
		(at 157.301105 113.4036)
		(size 0.4064)
		(drill 0.254)
		(layers "F.Cu" "B.Cu")
		(net "GND")
	)
	(via
		(at 139.053105 110.8896)
		(size 0.4064)
		(drill 0.254)
		(layers "F.Cu" "B.Cu")
		(net "GND")
	)
	(via
		(at 144.768105 99.4596)
		(size 0.4064)
		(drill 0.254)
		(layers "F.Cu" "B.Cu")
		(net "GND")
	)
	(via
		(at 145.149105 94.1256)
		(size 0.4064)
		(drill 0.254)
		(layers "F.Cu" "B.Cu")
		(net "GND")
	)
	(via
		(at 144.387105 98.6976)
		(size 0.4064)
		(drill 0.254)
		(layers "F.Cu" "B.Cu")
		(net "GND")
	)
	(via
		(at 139.053105 107.8416)
		(size 0.4064)
		(drill 0.254)
		(layers "F.Cu" "B.Cu")
		(net "GND")
	)
	(via
		(at 144.387105 84.9816)
		(size 0.4064)
		(drill 0.254)
		(layers "F.Cu" "B.Cu")
		(net "GND")
	)
	(via
		(at 152.388105 85.7436)
		(size 0.4064)
		(drill 0.254)
		(layers "F.Cu" "B.Cu")
		(net "GND")
	)
	(via
		(at 140.196105 93.3636)
		(size 0.4064)
		(drill 0.254)
		(layers "F.Cu" "B.Cu")
		(net "GND")
	)
	(via
		(at 139.815105 89.5536)
		(size 0.4064)
		(drill 0.254)
		(layers "F.Cu" "B.Cu")
		(net "GND")
	)
	(via
		(at 139.053105 106.3176)
		(size 0.4064)
		(drill 0.254)
		(layers "F.Cu" "B.Cu")
		(net "GND")
	)
	(via
		(at 141.841885 94.54338)
		(size 0.4064)
		(drill 0.254)
		(layers "F.Cu" "B.Cu")
		(net "GND")
	)
	(via
		(at 139.434105 93.3636)
		(size 0.4064)
		(drill 0.254)
		(layers "F.Cu" "B.Cu")
		(net "GND")
	)
	(via
		(at 158.701105 119.9036)
		(size 0.4064)
		(drill 0.254)
		(layers "F.Cu" "B.Cu")
		(net "GND")
	)
	(via
		(at 156.198105 85.7436)
		(size 0.4064)
		(drill 0.254)
		(layers "F.Cu" "B.Cu")
		(net "GND")
	)
	(via
		(at 149.801105 122.5036)
		(size 0.4064)
		(drill 0.254)
		(layers "F.Cu" "B.Cu")
		(net "GND")
	)
	(via
		(at 141.483125 88.62131)
		(size 0.4064)
		(drill 0.254)
		(layers "F.Cu" "B.Cu")
		(net "GND")
	)
	(via
		(at 146.292105 93.3636)
		(size 0.4064)
		(drill 0.254)
		(layers "F.Cu" "B.Cu")
		(net "GND")
	)
	(via
		(at 144.387105 88.0296)
		(size 0.4064)
		(drill 0.254)
		(layers "F.Cu" "B.Cu")
		(net "GND")
	)
	(via
		(at 139.053105 116.9856)
		(size 0.4064)
		(drill 0.254)
		(layers "F.Cu" "B.Cu")
		(net "GND")
	)
	(via
		(at 157.722105 87.2676)
		(size 0.4064)
		(drill 0.254)
		(layers "F.Cu" "B.Cu")
		(net "GND")
	)
	(via
		(at 140.649605 90.68482)
		(size 0.4064)
		(drill 0.254)
		(layers "F.Cu" "B.Cu")
		(net "GND")
	)
	(via
		(at 141.601105 86.65588)
		(size 0.4064)
		(drill 0.254)
		(layers "F.Cu" "B.Cu")
		(net "GND")
	)
	(via
		(at 158.103105 84.9816)
		(size 0.4064)
		(drill 0.254)
		(layers "F.Cu" "B.Cu")
		(net "GND")
	)
	(via
		(at 143.701105 86.6036)
		(size 0.4064)
		(drill 0.254)
		(layers "F.Cu" "B.Cu")
		(net "GND")
	)
	(via
		(at 151.201105 122.4036)
		(size 0.4064)
		(drill 0.254)
		(layers "F.Cu" "B.Cu")
		(net "GND")
	)
	(via
		(at 139.053105 112.4136)
		(size 0.4064)
		(drill 0.254)
		(layers "F.Cu" "B.Cu")
		(net "GND")
	)
	(via
		(at 140.577105 95.6496)
		(size 0.4064)
		(drill 0.254)
		(layers "F.Cu" "B.Cu")
		(net "GND")
	)
	(via
		(at 138.672105 104.0316)
		(size 0.4064)
		(drill 0.254)
		(layers "F.Cu" "B.Cu")
		(net "GND")
	)
	(via
		(at 138.672105 100.9836)
		(size 0.4064)
		(drill 0.254)
		(layers "F.Cu" "B.Cu")
		(net "GND")
	)
	(via
		(at 157.812285 119.80396)
		(size 0.4064)
		(drill 0.254)
		(layers "F.Cu" "B.Cu")
		(net "GND")
	)
	(via
		(at 142.482105 88.7916)
		(size 0.4064)
		(drill 0.254)
		(layers "F.Cu" "B.Cu")
		(net "GND")
	)
	(via
		(at 139.434105 110.1276)
		(size 0.4064)
		(drill 0.254)
		(layers "F.Cu" "B.Cu")
		(net "GND")
	)
	(via
		(at 145.911105 98.6976)
		(size 0.4064)
		(drill 0.254)
		(layers "F.Cu" "B.Cu")
		(net "GND")
	)
	(via
		(at 141.879325 88.05687)
		(size 0.4064)
		(drill 0.254)
		(layers "F.Cu" "B.Cu")
		(net "GND")
	)
	(via
		(at 157.401105 117.0036)
		(size 0.4064)
		(drill 0.254)
		(layers "F.Cu" "B.Cu")
		(net "GND")
	)
	(via
		(at 153.531105 86.5056)
		(size 0.4064)
		(drill 0.254)
		(layers "F.Cu" "B.Cu")
		(net "GND")
	)
	(via
		(at 156.579105 84.9816)
		(size 0.4064)
		(drill 0.254)
		(layers "F.Cu" "B.Cu")
		(net "GND")
	)
	(via
		(at 142.127795 90.90671)
		(size 0.4064)
		(drill 0.254)
		(layers "F.Cu" "B.Cu")
		(net "GND")
	)
	(via
		(at 157.722105 111.6516)
		(size 0.4064)
		(drill 0.254)
		(layers "F.Cu" "B.Cu")
		(net "GND")
	)
	(via
		(at 153.531105 84.9816)
		(size 0.4064)
		(drill 0.254)
		(layers "F.Cu" "B.Cu")
		(net "GND")
	)
	(via
		(at 141.402135 109.9838)
		(size 0.4064)
		(drill 0.254)
		(layers "F.Cu" "B.Cu")
		(net "GND")
	)
	(via
		(at 141.008675 93.32358)
		(size 0.4064)
		(drill 0.254)
		(layers "F.Cu" "B.Cu")
		(net "GND")
	)
	(via
		(at 144.447955 113.89913)
		(size 0.4064)
		(drill 0.254)
		(layers "F.Cu" "B.Cu")
		(net "GND")
	)
	(via
		(at 140.658675 92.72358)
		(size 0.4064)
		(drill 0.254)
		(layers "F.Cu" "B.Cu")
		(net "GND")
	)
	(via
		(at 139.434105 104.0316)
		(size 0.4064)
		(drill 0.254)
		(layers "F.Cu" "B.Cu")
		(net "GND")
	)
	(via
		(at 138.140655 121.80652)
		(size 0.4064)
		(drill 0.254)
		(layers "F.Cu" "B.Cu")
		(net "GND")
	)
	(via
		(at 147.054105 87.2676)
		(size 0.4064)
		(drill 0.254)
		(layers "F.Cu" "B.Cu")
		(net "GND")
	)
	(via
		(at 153.912105 87.2676)
		(size 0.4064)
		(drill 0.254)
		(layers "F.Cu" "B.Cu")
		(net "GND")
	)
	(via
		(at 143.943595 94.54338)
		(size 0.4064)
		(drill 0.254)
		(layers "F.Cu" "B.Cu")
		(net "GND")
	)
	(via
		(at 144.768105 88.7916)
		(size 0.4064)
		(drill 0.254)
		(layers "F.Cu" "B.Cu")
		(net "GND")
	)
	(via
		(at 158.301105 106.7036)
		(size 0.4064)
		(drill 0.254)
		(layers "F.Cu" "B.Cu")
		(net "GND")
	)
	(via
		(at 140.958105 97.9356)
		(size 0.4064)
		(drill 0.254)
		(layers "F.Cu" "B.Cu")
		(net "GND")
	)
	(via
		(at 138.672105 111.6516)
		(size 0.4064)
		(drill 0.254)
		(layers "F.Cu" "B.Cu")
		(net "GND")
	)
	(via
		(at 141.720105 99.4596)
		(size 0.4064)
		(drill 0.254)
		(layers "F.Cu" "B.Cu")
		(net "GND")
	)
	(via
		(at 139.434105 111.6516)
		(size 0.4064)
		(drill 0.254)
		(layers "F.Cu" "B.Cu")
		(net "GND")
	)
	(via
		(at 147.435105 88.0296)
		(size 0.4064)
		(drill 0.254)
		(layers "F.Cu" "B.Cu")
		(net "GND")
	)
	(via
		(at 144.006105 85.7436)
		(size 0.4064)
		(drill 0.254)
		(layers "F.Cu" "B.Cu")
		(net "GND")
	)
	(via
		(at 143.244105 97.9356)
		(size 0.4064)
		(drill 0.254)
		(layers "F.Cu" "B.Cu")
		(net "GND")
	)
	(via
		(at 152.388105 87.2676)
		(size 0.4064)
		(drill 0.254)
		(layers "F.Cu" "B.Cu")
		(net "GND")
	)
	(via
		(at 140.958105 99.4596)
		(size 0.4064)
		(drill 0.254)
		(layers "F.Cu" "B.Cu")
		(net "GND")
	)
	(via
		(at 144.006105 93.3636)
		(size 0.4064)
		(drill 0.254)
		(layers "F.Cu" "B.Cu")
		(net "GND")
	)
	(via
		(at 144.801105 122.2036)
		(size 0.4064)
		(drill 0.254)
		(layers "F.Cu" "B.Cu")
		(net "GND")
	)
	(via
		(at 146.292105 99.4596)
		(size 0.4064)
		(drill 0.254)
		(layers "F.Cu" "B.Cu")
		(net "GND")
	)
	(via
		(at 140.958105 85.7436)
		(size 0.4064)
		(drill 0.254)
		(layers "F.Cu" "B.Cu")
		(net "GND")
	)
	(via
		(at 140.196105 99.4596)
		(size 0.4064)
		(drill 0.254)
		(layers "F.Cu" "B.Cu")
		(net "GND")
	)
	(via
		(at 142.863105 88.0296)
		(size 0.4064)
		(drill 0.254)
		(layers "F.Cu" "B.Cu")
		(net "GND")
	)
	(via
		(at 139.053105 101.7456)
		(size 0.4064)
		(drill 0.254)
		(layers "F.Cu" "B.Cu")
		(net "GND")
	)
	(via
		(at 143.100935 94.59391)
		(size 0.4064)
		(drill 0.254)
		(layers "F.Cu" "B.Cu")
		(net "GND")
	)
	(via
		(at 140.577105 94.1256)
		(size 0.4064)
		(drill 0.254)
		(layers "F.Cu" "B.Cu")
		(net "GND")
	)
	(via
		(at 143.801105 122.2036)
		(size 0.4064)
		(drill 0.254)
		(layers "F.Cu" "B.Cu")
		(net "GND")
	)
	(via
		(at 138.672105 117.7476)
		(size 0.4064)
		(drill 0.254)
		(layers "F.Cu" "B.Cu")
		(net "GND")
	)
	(via
		(at 154.293105 86.5056)
		(size 0.4064)
		(drill 0.254)
		(layers "F.Cu" "B.Cu")
		(net "GND")
	)
	(via
		(at 139.001105 120.97242)
		(size 0.4064)
		(drill 0.254)
		(layers "F.Cu" "B.Cu")
		(net "GND")
	)
	(via
		(at 138.780215 121.8036)
		(size 0.4064)
		(drill 0.254)
		(layers "F.Cu" "B.Cu")
		(net "GND")
	)
	(via
		(at 139.053105 89.5536)
		(size 0.4064)
		(drill 0.254)
		(layers "F.Cu" "B.Cu")
		(net "GND")
	)
	(via
		(at 156.960105 85.7436)
		(size 0.4064)
		(drill 0.254)
		(layers "F.Cu" "B.Cu")
		(net "GND")
	)
	(via
		(at 156.501105 90.6036)
		(size 0.4064)
		(drill 0.254)
		(layers "F.Cu" "B.Cu")
		(net "GND")
	)
	(via
		(at 150.864105 87.2676)
		(size 0.4064)
		(drill 0.254)
		(layers "F.Cu" "B.Cu")
		(net "GND")
	)
	(via
		(at 145.149105 84.9816)
		(size 0.4064)
		(drill 0.254)
		(layers "F.Cu" "B.Cu")
		(net "GND")
	)
	(via
		(at 139.053105 98.6976)
		(size 0.4064)
		(drill 0.254)
		(layers "F.Cu" "B.Cu")
		(net "GND")
	)
	(via
		(at 139.434105 88.7916)
		(size 0.4064)
		(drill 0.254)
		(layers "F.Cu" "B.Cu")
		(net "GND")
	)
	(via
		(at 158.001105 102.1036)
		(size 0.4064)
		(drill 0.254)
		(layers "F.Cu" "B.Cu")
		(net "GND")
	)
	(via
		(at 158.865105 84.9816)
		(size 0.4064)
		(drill 0.254)
		(layers "F.Cu" "B.Cu")
		(net "GND")
	)
	(via
		(at 147.054105 96.4116)
		(size 0.4064)
		(drill 0.254)
		(layers "F.Cu" "B.Cu")
		(net "GND")
	)
	(via
		(at 138.672105 94.8876)
		(size 0.4064)
		(drill 0.254)
		(layers "F.Cu" "B.Cu")
		(net "GND")
	)
	(via
		(at 138.672105 113.1756)
		(size 0.4064)
		(drill 0.254)
		(layers "F.Cu" "B.Cu")
		(net "GND")
	)
	(via
		(at 145.149105 92.6016)
		(size 0.4064)
		(drill 0.254)
		(layers "F.Cu" "B.Cu")
		(net "GND")
	)
	(via
		(at 145.401105 90.0036)
		(size 0.4064)
		(drill 0.254)
		(layers "F.Cu" "B.Cu")
		(net "GND")
	)
	(via
		(at 148.197105 89.5536)
		(size 0.4064)
		(drill 0.254)
		(layers "F.Cu" "B.Cu")
		(net "GND")
	)
	(via
		(at 138.672105 110.1276)
		(size 0.4064)
		(drill 0.254)
		(layers "F.Cu" "B.Cu")
		(net "GND")
	)
	(via
		(at 138.401105 86.5036)
		(size 0.4064)
		(drill 0.254)
		(layers "F.Cu" "B.Cu")
		(net "GND")
	)
	(via
		(at 139.434105 107.0796)
		(size 0.4064)
		(drill 0.254)
		(layers "F.Cu" "B.Cu")
		(net "GND")
	)
	(via
		(at 138.672105 88.7916)
		(size 0.4064)
		(drill 0.254)
		(layers "F.Cu" "B.Cu")
		(net "GND")
	)
	(via
		(at 140.196105 94.8876)
		(size 0.4064)
		(drill 0.254)
		(layers "F.Cu" "B.Cu")
		(net "GND")
	)
	(via
		(at 158.103105 86.5056)
		(size 0.4064)
		(drill 0.254)
		(layers "F.Cu" "B.Cu")
		(net "GND")
	)
	(via
		(at 141.339105 84.9816)
		(size 0.4064)
		(drill 0.254)
		(layers "F.Cu" "B.Cu")
		(net "GND")
	)
	(via
		(at 139.815105 94.1256)
		(size 0.4064)
		(drill 0.254)
		(layers "F.Cu" "B.Cu")
		(net "GND")
	)
	(via
		(at 153.150105 87.2676)
		(size 0.4064)
		(drill 0.254)
		(layers "F.Cu" "B.Cu")
		(net "GND")
	)
	(via
		(at 147.816105 88.7916)
		(size 0.4064)
		(drill 0.254)
		(layers "F.Cu" "B.Cu")
		(net "GND")
	)
	(via
		(at 146.801105 122.6036)
		(size 0.4064)
		(drill 0.254)
		(layers "F.Cu" "B.Cu")
		(net "GND")
	)
	(via
		(at 156.960105 87.2676)
		(size 0.4064)
		(drill 0.254)
		(layers "F.Cu" "B.Cu")
		(net "GND")
	)
	(via
		(at 145.149105 88.0296)
		(size 0.4064)
		(drill 0.254)
		(layers "F.Cu" "B.Cu")
		(net "GND")
	)
	(via
		(at 138.672105 97.9356)
		(size 0.4064)
		(drill 0.254)
		(layers "F.Cu" "B.Cu")
		(net "GND")
	)
	(via
		(at 148.601105 122.5036)
		(size 0.4064)
		(drill 0.254)
		(layers "F.Cu" "B.Cu")
		(net "GND")
	)
	(via
		(at 139.434105 117.7476)
		(size 0.4064)
		(drill 0.254)
		(layers "F.Cu" "B.Cu")
		(net "GND")
	)
	(via
		(at 144.768105 85.7436)
		(size 0.4064)
		(drill 0.254)
		(layers "F.Cu" "B.Cu")
		(net "GND")
	)
	(via
		(at 139.434105 100.9836)
		(size 0.4064)
		(drill 0.254)
		(layers "F.Cu" "B.Cu")
		(net "GND")
	)
	(via
		(at 146.292105 97.9356)
		(size 0.4064)
		(drill 0.254)
		(layers "F.Cu" "B.Cu")
		(net "GND")
	)
	(via
		(at 146.673105 88.0296)
		(size 0.4064)
		(drill 0.254)
		(layers "F.Cu" "B.Cu")
		(net "GND")
	)
	(via
		(at 156.301105 111.2036)
		(size 0.4064)
		(drill 0.254)
		(layers "F.Cu" "B.Cu")
		(net "GND")
	)
	(via
		(at 139.053105 113.9376)
		(size 0.4064)
		(drill 0.254)
		(layers "F.Cu" "B.Cu")
		(net "GND")
	)
	(via
		(at 139.053105 94.1256)
		(size 0.4064)
		(drill 0.254)
		(layers "F.Cu" "B.Cu")
		(net "GND")
	)
	(via
		(at 142.524895 93.42358)
		(size 0.4064)
		(drill 0.254)
		(layers "F.Cu" "B.Cu")
		(net "GND")
	)
	(via
		(at 147.816105 91.8396)
		(size 0.4064)
		(drill 0.254)
		(layers "F.Cu" "B.Cu")
		(net "GND")
	)
	(via
		(at 157.401105 115.9036)
		(size 0.4064)
		(drill 0.254)
		(layers "F.Cu" "B.Cu")
		(net "GND")
	)
	(via
		(at 142.166205 91.55085)
		(size 0.4064)
		(drill 0.254)
		(layers "F.Cu" "B.Cu")
		(net "GND")
	)
	(via
		(at 139.053105 103.2696)
		(size 0.4064)
		(drill 0.254)
		(layers "F.Cu" "B.Cu")
		(net "GND")
	)
	(via
		(at 146.673105 97.1736)
		(size 0.4064)
		(drill 0.254)
		(layers "F.Cu" "B.Cu")
		(net "GND")
	)
	(via
		(at 145.530105 85.7436)
		(size 0.4064)
		(drill 0.254)
		(layers "F.Cu" "B.Cu")
		(net "GND")
	)
	(via
		(at 139.053105 97.1736)
		(size 0.4064)
		(drill 0.254)
		(layers "F.Cu" "B.Cu")
		(net "GND")
	)
	(via
		(at 145.530105 99.4596)
		(size 0.4064)
		(drill 0.254)
		(layers "F.Cu" "B.Cu")
		(net "GND")
	)
	(via
		(at 140.577105 84.9816)
		(size 0.4064)
		(drill 0.254)
		(layers "F.Cu" "B.Cu")
		(net "GND")
	)
	(via
		(at 157.501105 118.1686)
		(size 0.4064)
		(drill 0.254)
		(layers "F.Cu" "B.Cu")
		(net "GND")
	)
	(via
		(at 139.434105 114.6996)
		(size 0.4064)
		(drill 0.254)
		(layers "F.Cu" "B.Cu")
		(net "GND")
	)
	(via
		(at 156.801105 122.3036)
		(size 0.4064)
		(drill 0.254)
		(layers "F.Cu" "B.Cu")
		(net "GND")
	)
	(via
		(at 153.912105 85.7436)
		(size 0.4064)
		(drill 0.254)
		(layers "F.Cu" "B.Cu")
		(net "GND")
	)
	(via
		(at 141.697285 89.23223)
		(size 0.4064)
		(drill 0.254)
		(layers "F.Cu" "B.Cu")
		(net "GND")
	)
	(via
		(at 144.006105 87.2676)
		(size 0.4064)
		(drill 0.254)
		(layers "F.Cu" "B.Cu")
		(net "GND")
	)
	(via
		(at 145.530105 88.7916)
		(size 0.4064)
		(drill 0.254)
		(layers "F.Cu" "B.Cu")
		(net "GND")
	)
	(via
		(at 155.817105 86.5056)
		(size 0.4064)
		(drill 0.254)
		(layers "F.Cu" "B.Cu")
		(net "GND")
	)
	(via
		(at 144.387105 94.1256)
		(size 0.4064)
		(drill 0.254)
		(layers "F.Cu" "B.Cu")
		(net "GND")
	)
	(via
		(at 139.053105 109.3656)
		(size 0.4064)
		(drill 0.254)
		(layers "F.Cu" "B.Cu")
		(net "GND")
	)
	(via
		(at 139.815105 92.6016)
		(size 0.4064)
		(drill 0.254)
		(layers "F.Cu" "B.Cu")
		(net "GND")
	)
	(via
		(at 141.101105 94.5234)
		(size 0.4064)
		(drill 0.254)
		(layers "F.Cu" "B.Cu")
		(net "GND")
	)
	(via
		(at 152.007105 84.9816)
		(size 0.4064)
		(drill 0.254)
		(layers "F.Cu" "B.Cu")
		(net "GND")
	)
	(via
		(at 140.196105 97.9356)
		(size 0.4064)
		(drill 0.254)
		(layers "F.Cu" "B.Cu")
		(net "GND")
	)
	(via
		(at 139.815105 95.6496)
		(size 0.4064)
		(drill 0.254)
		(layers "F.Cu" "B.Cu")
		(net "GND")
	)
	(via
		(at 148.101105 115.4036)
		(size 0.4064)
		(drill 0.254)
		(layers "F.Cu" "B.Cu")
		(net "GND")
	)
	(via
		(at 157.119785 120.88636)
		(size 0.4064)
		(drill 0.254)
		(layers "F.Cu" "B.Cu")
		(net "GND")
	)
	(via
		(at 155.436105 85.7436)
		(size 0.4064)
		(drill 0.254)
		(layers "F.Cu" "B.Cu")
		(net "GND")
	)
	(via
		(at 157.301105 114.3036)
		(size 0.4064)
		(drill 0.254)
		(layers "F.Cu" "B.Cu")
		(net "GND")
	)
	(via
		(at 139.434105 116.2236)
		(size 0.4064)
		(drill 0.254)
		(layers "F.Cu" "B.Cu")
		(net "GND")
	)
	(via
		(at 139.434105 91.8396)
		(size 0.4064)
		(drill 0.254)
		(layers "F.Cu" "B.Cu")
		(net "GND")
	)
	(via
		(at 148.197105 88.0296)
		(size 0.4064)
		(drill 0.254)
		(layers "F.Cu" "B.Cu")
		(net "GND")
	)
	(via
		(at 147.054105 97.9356)
		(size 0.4064)
		(drill 0.254)
		(layers "F.Cu" "B.Cu")
		(net "GND")
	)
	(via
		(at 157.088415 121.53481)
		(size 0.4064)
		(drill 0.254)
		(layers "F.Cu" "B.Cu")
		(net "GND")
	)
	(via
		(at 157.341105 86.5056)
		(size 0.4064)
		(drill 0.254)
		(layers "F.Cu" "B.Cu")
		(net "GND")
	)
	(via
		(at 139.434105 113.1756)
		(size 0.4064)
		(drill 0.254)
		(layers "F.Cu" "B.Cu")
		(net "GND")
	)
	(via
		(at 156.198105 87.2676)
		(size 0.4064)
		(drill 0.254)
		(layers "F.Cu" "B.Cu")
		(net "GND")
	)
	(via
		(at 139.053105 120.0336)
		(size 0.4064)
		(drill 0.254)
		(layers "F.Cu" "B.Cu")
		(net "GND")
	)
	(via
		(at 138.401105 85.2036)
		(size 0.4064)
		(drill 0.254)
		(layers "F.Cu" "B.Cu")
		(net "GND")
	)
	(via
		(at 139.953375 88.2536)
		(size 0.4064)
		(drill 0.254)
		(layers "F.Cu" "B.Cu")
		(net "GND")
	)
	(via
		(at 157.341105 84.9816)
		(size 0.4064)
		(drill 0.254)
		(layers "F.Cu" "B.Cu")
		(net "GND")
	)
	(via
		(at 139.434105 102.5076)
		(size 0.4064)
		(drill 0.254)
		(layers "F.Cu" "B.Cu")
		(net "GND")
	)
	(via
		(at 139.053105 95.6496)
		(size 0.4064)
		(drill 0.254)
		(layers "F.Cu" "B.Cu")
		(net "GND")
	)
	(via
		(at 155.817105 84.9816)
		(size 0.4064)
		(drill 0.254)
		(layers "F.Cu" "B.Cu")
		(net "GND")
	)
	(via
		(at 139.053105 100.2216)
		(size 0.4064)
		(drill 0.254)
		(layers "F.Cu" "B.Cu")
		(net "GND")
	)
	(via
		(at 156.579105 86.5056)
		(size 0.4064)
		(drill 0.254)
		(layers "F.Cu" "B.Cu")
		(net "GND")
	)
	(via
		(at 144.006105 88.7916)
		(size 0.4064)
		(drill 0.254)
		(layers "F.Cu" "B.Cu")
		(net "GND")
	)
	(via
		(at 144.006105 99.4596)
		(size 0.4064)
		(drill 0.254)
		(layers "F.Cu" "B.Cu")
		(net "GND")
	)
	(via
		(at 139.815105 91.0776)
		(size 0.4064)
		(drill 0.254)
		(layers "F.Cu" "B.Cu")
		(net "GND")
	)
	(via
		(at 138.672105 99.4596)
		(size 0.4064)
		(drill 0.254)
		(layers "F.Cu" "B.Cu")
		(net "GND")
	)
	(via
		(at 138.672105 93.3636)
		(size 0.4064)
		(drill 0.254)
		(layers "F.Cu" "B.Cu")
		(net "GND")
	)
	(via
		(at 138.672105 96.4116)
		(size 0.4064)
		(drill 0.254)
		(layers "F.Cu" "B.Cu")
		(net "GND")
	)
	(via
		(at 158.101105 98.4036)
		(size 0.4064)
		(drill 0.254)
		(layers "F.Cu" "B.Cu")
		(net "GND")
	)
	(via
		(at 138.672105 91.8396)
		(size 0.4064)
		(drill 0.254)
		(layers "F.Cu" "B.Cu")
		(net "GND")
	)
	(via
		(at 146.292105 87.2676)
		(size 0.4064)
		(drill 0.254)
		(layers "F.Cu" "B.Cu")
		(net "GND")
	)
	(via
		(at 140.672965 91.3036)
		(size 0.4064)
		(drill 0.254)
		(layers "F.Cu" "B.Cu")
		(net "GND")
	)
	(via
		(at 152.007105 86.5056)
		(size 0.4064)
		(drill 0.254)
		(layers "F.Cu" "B.Cu")
		(net "GND")
	)
	(via
		(at 148.578105 88.7916)
		(size 0.4064)
		(drill 0.254)
		(layers "F.Cu" "B.Cu")
		(net "GND")
	)
	(via
		(at 142.959065 93.99413)
		(size 0.4064)
		(drill 0.254)
		(layers "F.Cu" "B.Cu")
		(net "GND")
	)
	(via
		(at 158.101105 99.2036)
		(size 0.4064)
		(drill 0.254)
		(layers "F.Cu" "B.Cu")
		(net "GND")
	)
	(via
		(at 147.054105 91.8396)
		(size 0.4064)
		(drill 0.254)
		(layers "F.Cu" "B.Cu")
		(net "GND")
	)
	(via
		(at 138.672105 90.3156)
		(size 0.4064)
		(drill 0.254)
		(layers "F.Cu" "B.Cu")
		(net "GND")
	)
	(via
		(at 153.150105 85.7436)
		(size 0.4064)
		(drill 0.254)
		(layers "F.Cu" "B.Cu")
		(net "GND")
	)
	(via
		(at 138.672105 105.5556)
		(size 0.4064)
		(drill 0.254)
		(layers "F.Cu" "B.Cu")
		(net "GND")
	)
	(via
		(at 139.434105 119.2716)
		(size 0.4064)
		(drill 0.254)
		(layers "F.Cu" "B.Cu")
		(net "GND")
	)
	(via
		(at 145.911105 92.6016)
		(size 0.4064)
		(drill 0.254)
		(layers "F.Cu" "B.Cu")
		(net "GND")
	)
	(via
		(at 158.101105 100.1036)
		(size 0.4064)
		(drill 0.254)
		(layers "F.Cu" "B.Cu")
		(net "GND")
	)
	(via
		(at 139.053105 118.5096)
		(size 0.4064)
		(drill 0.254)
		(layers "F.Cu" "B.Cu")
		(net "GND")
	)
	(via
		(at 139.801105 87.6286)
		(size 0.4064)
		(drill 0.254)
		(layers "F.Cu" "B.Cu")
		(net "GND")
	)
	(via
		(at 158.635425 118.9036)
		(size 0.4064)
		(drill 0.254)
		(layers "F.Cu" "B.Cu")
		(net "GND")
	)
	(via
		(at 139.434105 94.8876)
		(size 0.4064)
		(drill 0.254)
		(layers "F.Cu" "B.Cu")
		(net "GND")
	)
	(via
		(at 140.196105 96.4116)
		(size 0.4064)
		(drill 0.254)
		(layers "F.Cu" "B.Cu")
		(net "GND")
	)
	(via
		(at 141.720105 97.9356)
		(size 0.4064)
		(drill 0.254)
		(layers "F.Cu" "B.Cu")
		(net "GND")
	)
	(via
		(at 139.434105 105.5556)
		(size 0.4064)
		(drill 0.254)
		(layers "F.Cu" "B.Cu")
		(net "GND")
	)
	(via
		(at 155.436105 87.2676)
		(size 0.4064)
		(drill 0.254)
		(layers "F.Cu" "B.Cu")
		(net "GND")
	)
	(via
		(at 155.201105 92.0036)
		(size 0.4064)
		(drill 0.254)
		(layers "F.Cu" "B.Cu")
		(net "GND")
	)
	(via
		(at 140.577105 98.6976)
		(size 0.4064)
		(drill 0.254)
		(layers "F.Cu" "B.Cu")
		(net "GND")
	)
	(via
		(at 158.101105 104.5036)
		(size 0.4064)
		(drill 0.254)
		(layers "F.Cu" "B.Cu")
		(net "GND")
	)
	(via
		(at 151.245105 86.5056)
		(size 0.4064)
		(drill 0.254)
		(layers "F.Cu" "B.Cu")
		(net "GND")
	)
	(via
		(at 140.801105 86.65588)
		(size 0.4064)
		(drill 0.254)
		(layers "F.Cu" "B.Cu")
		(net "GND")
	)
	(via
		(at 145.530105 93.3636)
		(size 0.4064)
		(drill 0.254)
		(layers "F.Cu" "B.Cu")
		(net "GND")
	)
	(via
		(at 140.716245 92.02261)
		(size 0.4064)
		(drill 0.254)
		(layers "F.Cu" "B.Cu")
		(net "GND")
	)
	(via
		(at 138.672105 114.6996)
		(size 0.4064)
		(drill 0.254)
		(layers "F.Cu" "B.Cu")
		(net "GND")
	)
	(via
		(at 143.244105 93.3636)
		(size 0.4064)
		(drill 0.254)
		(layers "F.Cu" "B.Cu")
		(net "GND")
	)
	(via
		(at 138.672105 108.6036)
		(size 0.4064)
		(drill 0.254)
		(layers "F.Cu" "B.Cu")
		(net "GND")
	)
	(via
		(at 158.484105 87.2676)
		(size 0.4064)
		(drill 0.254)
		(layers "F.Cu" "B.Cu")
		(net "GND")
	)
	(via
		(at 158.865105 86.5056)
		(size 0.4064)
		(drill 0.254)
		(layers "F.Cu" "B.Cu")
		(net "GND")
	)
	(via
		(at 138.672105 107.0796)
		(size 0.4064)
		(drill 0.254)
		(layers "F.Cu" "B.Cu")
		(net "GND")
	)
	(via
		(at 154.293105 84.9816)
		(size 0.4064)
		(drill 0.254)
		(layers "F.Cu" "B.Cu")
		(net "GND")
	)
	(via
		(at 142.101105 98.6976)
		(size 0.4064)
		(drill 0.254)
		(layers "F.Cu" "B.Cu")
		(net "GND")
	)
	(via
		(at 152.769105 86.5056)
		(size 0.4064)
		(drill 0.254)
		(layers "F.Cu" "B.Cu")
		(net "GND")
	)
	(via
		(at 145.911105 89.5536)
		(size 0.4064)
		(drill 0.254)
		(layers "F.Cu" "B.Cu")
		(net "GND")
	)
	(via
		(at 138.672105 102.5076)
		(size 0.4064)
		(drill 0.254)
		(layers "F.Cu" "B.Cu")
		(net "GND")
	)
	(via
		(at 148.501105 84.00359)
		(size 5.5)
		(drill 3.5)
		(layers "F.Cu" "B.Cu")
		(padstack
			(mode front_inner_back)
			(layer "Inner"
				(size 5.5)
			)
			(layer "B.Cu"
				(size 6)
			)
		)
		(net "GND")
	)
	(via
		(at 145.911105 86.5056)
		(size 0.4064)
		(drill 0.254)
		(layers "F.Cu" "B.Cu")
		(net "GND")
	)
	(via
		(at 147.435105 89.5536)
		(size 0.4064)
		(drill 0.254)
		(layers "F.Cu" "B.Cu")
		(net "GND")
	)
	(via
		(at 145.530105 87.2676)
		(size 0.4064)
		(drill 0.254)
		(layers "F.Cu" "B.Cu")
		(net "GND")
	)
	(via
		(at 145.149105 98.6976)
		(size 0.4064)
		(drill 0.254)
		(layers "F.Cu" "B.Cu")
		(net "GND")
	)
	(via
		(at 143.244105 88.7916)
		(size 0.4064)
		(drill 0.254)
		(layers "F.Cu" "B.Cu")
		(net "GND")
	)
	(via
		(at 158.484105 85.7436)
		(size 0.4064)
		(drill 0.254)
		(layers "F.Cu" "B.Cu")
		(net "GND")
	)
	(via
		(at 144.387105 92.6016)
		(size 0.4064)
		(drill 0.254)
		(layers "F.Cu" "B.Cu")
		(net "GND")
	)
	(via
		(at 143.625105 88.0296)
		(size 0.4064)
		(drill 0.254)
		(layers "F.Cu" "B.Cu")
		(net "GND")
	)
	(via
		(at 141.339105 98.6976)
		(size 0.4064)
		(drill 0.254)
		(layers "F.Cu" "B.Cu")
		(net "GND")
	)
	(via
		(at 139.434105 108.6036)
		(size 0.4064)
		(drill 0.254)
		(layers "F.Cu" "B.Cu")
		(net "GND")
	)
	(via
		(at 155.055105 84.9816)
		(size 0.4064)
		(drill 0.254)
		(layers "F.Cu" "B.Cu")
		(net "GND")
	)
	(via
		(at 154.674105 87.2676)
		(size 0.4064)
		(drill 0.254)
		(layers "F.Cu" "B.Cu")
		(net "GND")
	)
	(via
		(at 150.102105 87.2676)
		(size 0.4064)
		(drill 0.254)
		(layers "F.Cu" "B.Cu")
		(net "GND")
	)
	(via
		(at 145.911105 88.0296)
		(size 0.4064)
		(drill 0.254)
		(layers "F.Cu" "B.Cu")
		(net "GND")
	)
	(via
		(at 139.434105 97.9356)
		(size 0.4064)
		(drill 0.254)
		(layers "F.Cu" "B.Cu")
		(net "GND")
	)
	(via
		(at 157.722105 85.7436)
		(size 0.4064)
		(drill 0.254)
		(layers "F.Cu" "B.Cu")
		(net "GND")
	)
	(via
		(at 139.815105 98.6976)
		(size 0.4064)
		(drill 0.254)
		(layers "F.Cu" "B.Cu")
		(net "GND")
	)
	(via
		(at 146.673105 98.6976)
		(size 0.4064)
		(drill 0.254)
		(layers "F.Cu" "B.Cu")
		(net "GND")
	)
	(via
		(at 152.701105 122.4036)
		(size 0.4064)
		(drill 0.254)
		(layers "F.Cu" "B.Cu")
		(net "GND")
	)
	(via
		(at 144.768105 93.3636)
		(size 0.4064)
		(drill 0.254)
		(layers "F.Cu" "B.Cu")
		(net "GND")
	)
	(via
		(at 140.592045 90.02358)
		(size 0.4064)
		(drill 0.254)
		(layers "F.Cu" "B.Cu")
		(net "GND")
	)
	(via
		(at 151.626105 85.7436)
		(size 0.4064)
		(drill 0.254)
		(layers "F.Cu" "B.Cu")
		(net "GND")
	)
	(via
		(at 141.366185 93.96188)
		(size 0.4064)
		(drill 0.254)
		(layers "F.Cu" "B.Cu")
		(net "GND")
	)
	(via
		(at 139.053105 92.6016)
		(size 0.4064)
		(drill 0.254)
		(layers "F.Cu" "B.Cu")
		(net "GND")
	)
	(via
		(at 157.722105 108.6036)
		(size 0.4064)
		(drill 0.254)
		(layers "F.Cu" "B.Cu")
		(net "GND")
	)
	(via
		(at 146.673105 89.5536)
		(size 0.4064)
		(drill 0.254)
		(layers "F.Cu" "B.Cu")
		(net "GND")
	)
	(via
		(at 144.768105 87.2676)
		(size 0.4064)
		(drill 0.254)
		(layers "F.Cu" "B.Cu")
		(net "GND")
	)
	(via
		(at 142.482105 97.9356)
		(size 0.4064)
		(drill 0.254)
		(layers "F.Cu" "B.Cu")
		(net "GND")
	)
	(via
		(at 157.722105 110.1276)
		(size 0.4064)
		(drill 0.254)
		(layers "F.Cu" "B.Cu")
		(net "GND")
	)
	(via
		(at 139.434105 96.4116)
		(size 0.4064)
		(drill 0.254)
		(layers "F.Cu" "B.Cu")
		(net "GND")
	)
	(via
		(at 156.301105 112.4036)
		(size 0.4064)
		(drill 0.254)
		(layers "F.Cu" "B.Cu")
		(net "GND")
	)
	(via
		(at 144.387105 86.5056)
		(size 0.4064)
		(drill 0.254)
		(layers "F.Cu" "B.Cu")
		(net "GND")
	)
	(via
		(at 138.672105 116.2236)
		(size 0.4064)
		(drill 0.254)
		(layers "F.Cu" "B.Cu")
		(net "GND")
	)
	(via
		(at 158.280455 118.10292)
		(size 0.4064)
		(drill 0.254)
		(layers "F.Cu" "B.Cu")
		(net "GND")
	)
	(via
		(at 145.149105 86.5056)
		(size 0.4064)
		(drill 0.254)
		(layers "F.Cu" "B.Cu")
		(net "GND")
	)
	(via
		(at 146.673105 95.6496)
		(size 0.4064)
		(drill 0.254)
		(layers "F.Cu" "B.Cu")
		(net "GND")
	)
	(via
		(at 139.053105 104.7936)
		(size 0.4064)
		(drill 0.254)
		(layers "F.Cu" "B.Cu")
		(net "GND")
	)
	(via
		(at 152.769105 84.9816)
		(size 0.4064)
		(drill 0.254)
		(layers "F.Cu" "B.Cu")
		(net "GND")
	)
	(via
		(at 147.054105 94.8876)
		(size 0.4064)
		(drill 0.254)
		(layers "F.Cu" "B.Cu")
		(net "GND")
	)
	(via
		(at 147.001105 92.6036)
		(size 0.4064)
		(drill 0.254)
		(layers "F.Cu" "B.Cu")
		(net "GND")
	)
	(via
		(at 156.301105 110.0036)
		(size 0.4064)
		(drill 0.254)
		(layers "F.Cu" "B.Cu")
		(net "GND")
	)
	(via
		(at 154.674105 85.7436)
		(size 0.4064)
		(drill 0.254)
		(layers "F.Cu" "B.Cu")
		(net "GND")
	)
	(segment
		(start 152.101105 93.90547)
		(end 152.501105 93.50547)
		(width 0.254)
		(layer "F.Cu")
		(net "EXTIN")
	)
	(segment
		(start 152.501105 93.50547)
		(end 152.501105 93.3036)
		(width 0.254)
		(layer "F.Cu")
		(net "EXTIN")
	)
	(segment
		(start 152.100615 96.00379)
		(end 152.101105 96.0033)
		(width 0.254)
		(layer "F.Cu")
		(net "EXTIN")
	)
	(segment
		(start 152.101105 96.0033)
		(end 152.101105 93.90547)
		(width 0.254)
		(layer "F.Cu")
		(net "EXTIN")
	)
	(segment
		(start 155.201105 93.7036)
		(end 155.251105 93.7036)
		(width 0.254)
		(layer "F.Cu")
		(net "D_SEL")
	)
	(segment
		(start 154.300255 94.60445)
		(end 155.201105 93.7036)
		(width 0.254)
		(layer "F.Cu")
		(net "D_SEL")
	)
	(segment
		(start 155.251105 93.7036)
		(end 156.451105 92.5036)
		(width 0.254)
		(layer "F.Cu")
		(net "D_SEL")
	)
	(segment
		(start 154.300255 96.00379)
		(end 154.300255 94.60445)
		(width 0.254)
		(layer "F.Cu")
		(net "D_SEL")
	)
	(segment
		(start 156.451105 92.5036)
		(end 156.501105 92.5036)
		(width 0.254)
		(layer "F.Cu")
		(net "D_SEL")
	)
	(segment
		(start 151.774105 89.7806)
		(end 151.774105 89.4306)
		(width 0.254)
		(layer "F.Cu")
		(net "+3V3")
	)
	(segment
		(start 146.053395 114.11798)
		(end 146.060585 114.11079)
		(width 0.254)
		(layer "F.Cu")
		(net "+3V3")
	)
	(segment
		(start 149.631505 89.4886)
		(end 150.716105 89.4886)
		(width 0.254)
		(layer "F.Cu")
		(net "+3V3")
	)
	(segment
		(start 150.716105 89.4886)
		(end 151.001105 89.2036)
		(width 0.254)
		(layer "F.Cu")
		(net "+3V3")
	)
	(segment
		(start 151.774105 89.4306)
		(end 152.001105 89.2036)
		(width 0.254)
		(layer "F.Cu")
		(net "+3V3")
	)
	(segment
		(start 149.201105 113.9036)
		(end 149.201105 113.0786)
		(width 0.254)
		(layer "F.Cu")
		(net "+3V3")
	)
	(segment
		(start 147.701105 114.1036)
		(end 147.701105 113.0786)
		(width 0.254)
		(layer "F.Cu")
		(net "+3V3")
	)
	(segment
		(start 146.060585 114.11079)
		(end 147.693915 114.11079)
		(width 0.254)
		(layer "F.Cu")
		(net "+3V3")
	)
	(segment
		(start 151.601105 89.9036)
		(end 151.651105 89.9036)
		(width 0.254)
		(layer "F.Cu")
		(net "+3V3")
	)
	(segment
		(start 147.693915 114.11079)
		(end 147.701105 114.1036)
		(width 0.254)
		(layer "F.Cu")
		(net "+3V3")
	)
	(segment
		(start 148.701105 118.3036)
		(end 148.701105 117.32431)
		(width 0.254)
		(layer "F.Cu")
		(net "+3V3")
	)
	(segment
		(start 151.651105 89.9036)
		(end 151.774105 89.7806)
		(width 0.254)
		(layer "F.Cu")
		(net "+3V3")
	)
	(via
		(at 140.801105 122.2036)
		(size 0.4064)
		(drill 0.254)
		(layers "F.Cu" "B.Cu")
		(net "+3V3")
	)
	(via
		(at 151.001105 89.2036)
		(size 0.4064)
		(drill 0.254)
		(layers "F.Cu" "B.Cu")
		(net "+3V3")
	)
	(via
		(at 152.001105 89.2036)
		(size 0.4064)
		(drill 0.254)
		(layers "F.Cu" "B.Cu")
		(net "+3V3")
	)
	(via
		(at 153.401105 111.4536)
		(size 0.4064)
		(drill 0.254)
		(layers "F.Cu" "B.Cu")
		(net "+3V3")
	)
	(via
		(at 153.401105 112.06614)
		(size 0.4064)
		(drill 0.254)
		(layers "F.Cu" "B.Cu")
		(net "+3V3")
	)
	(via
		(at 140.789115 121.48701)
		(size 0.4064)
		(drill 0.254)
		(layers "F.Cu" "B.Cu")
		(net "+3V3")
	)
	(via
		(at 153.401105 110.8036)
		(size 0.4064)
		(drill 0.254)
		(layers "F.Cu" "B.Cu")
		(net "+3V3")
	)
	(via
		(at 149.201105 113.9036)
		(size 0.4064)
		(drill 0.254)
		(layers "F.Cu" "B.Cu")
		(net "+3V3")
	)
	(via
		(at 140.801105 120.83908)
		(size 0.4064)
		(drill 0.254)
		(layers "F.Cu" "B.Cu")
		(net "+3V3")
	)
	(via
		(at 140.801105 122.9036)
		(size 0.4064)
		(drill 0.254)
		(layers "F.Cu" "B.Cu")
		(net "+3V3")
	)
	(via
		(at 158.601105 122.0036)
		(size 0.4064)
		(drill 0.254)
		(layers "F.Cu" "B.Cu")
		(net "+3V3")
	)
	(via
		(at 147.701105 114.1036)
		(size 0.4064)
		(drill 0.254)
		(layers "F.Cu" "B.Cu")
		(net "+3V3")
	)
	(via
		(at 148.701105 118.3036)
		(size 0.4064)
		(drill 0.254)
		(layers "F.Cu" "B.Cu")
		(net "+3V3")
	)
	(via
		(at 157.912535 122.0036)
		(size 0.4064)
		(drill 0.254)
		(layers "F.Cu" "B.Cu")
		(net "+3V3")
	)
	(via
		(at 158.601105 121.21656)
		(size 0.4064)
		(drill 0.254)
		(layers "F.Cu" "B.Cu")
		(net "+3V3")
	)
	(via
		(at 157.846845 121.17806)
		(size 0.4064)
		(drill 0.254)
		(layers "F.Cu" "B.Cu")
		(net "+3V3")
	)
	(arc
		(start 148.701105 117.32431)
		(mid 148.7141 117.258982)
		(end 148.751105 117.2036)
		(width 0.254)
		(layer "F.Cu")
		(net "+3V3")
	)
	(segment
		(start 139.507105 124.4786)
		(end 139.507105 123.0036)
		(width 0.254)
		(layer "B.Cu")
		(net "+3V3")
	)
	(segment
		(start 157.507105 124.4786)
		(end 157.507105 122.5838)
		(width 0.254)
		(layer "B.Cu")
		(net "+3V3")
	)
	(segment
		(start 157.007105 124.4786)
		(end 157.007105 122.82484)
		(width 0.254)
		(layer "B.Cu")
		(net "+3V3")
	)
	(segment
		(start 140.507105 124.4786)
		(end 140.507105 122.8234)
		(width 0.254)
		(layer "B.Cu")
		(net "+3V3")
	)
	(segment
		(start 157.470715 122.5838)
		(end 157.507105 122.5838)
		(width 0.254)
		(layer "B.Cu")
		(net "+3V3")
	)
	(segment
		(start 140.007105 124.4786)
		(end 140.007105 122.80092)
		(width 0.254)
		(layer "B.Cu")
		(net "+3V3")
	)
	(zone
		(net "GND")
		(layer "F.Cu")
		(hatch edge 0.5)
		(priority 9)
		(connect_pads yes
			(clearance 0.5)
		)
		(min_thickness 0.25)
		(fill yes
			(thermal_gap 0.254)
			(thermal_bridge_width 0.508)
			(island_removal_mode 0)
		)
		(polygon
			(pts
				(xy 139.001105 123.5036) (xy 140.601105 123.5036) (xy 140.601105 120.9036) (xy 137.801105 120.9036)
				(xy 137.801105 122.2036) (xy 139.001105 122.2036)
			)
		)
	)
	(zone
		(net "GND")
		(layer "F.Cu")
		(hatch edge 0.5)
		(priority 2)
		(connect_pads yes
			(clearance 0.5)
		)
		(min_thickness 0.25)
		(fill yes
			(thermal_gap 0.254)
			(thermal_bridge_width 0.508)
			(island_removal_mode 0)
		)
		(polygon
			(pts
				(xy 137.501085 84.00359) (xy 159.501115 84.00359) (xy 159.501115 122.8536) (xy 137.501095 122.8536)
			)
		)
	)
	(zone
		(net "+3V3")
		(layer "F.Cu")
		(hatch edge 0.5)
		(priority 5)
		(connect_pads yes
			(clearance 0.5)
		)
		(min_thickness 0.25)
		(fill yes
			(thermal_gap 0.254)
			(thermal_bridge_width 0.508)
			(island_removal_mode 0)
		)
		(polygon
			(pts
				(xy 154.601105 108.43456) (xy 154.601105 112.6536) (xy 154.001105 112.6536) (xy 154.001105 117.8036)
				(xy 151.901105 117.8036) (xy 151.901105 112.2036) (xy 152.800385 112.2036) (xy 152.800385 108.43456)
			)
		)
	)
	(zone
		(net "GND")
		(layer "F.Cu")
		(hatch edge 0.5)
		(priority 7)
		(connect_pads yes
			(clearance 0.5)
		)
		(min_thickness 0.25)
		(fill yes
			(thermal_gap 0.254)
			(thermal_bridge_width 0.508)
			(island_removal_mode 0)
		)
		(polygon
			(pts
				(xy 156.507095 122.9036) (xy 156.507095 121.1036) (xy 157.801105 121.1036) (xy 157.801105 122.9036)
			)
		)
	)
	(zone
		(net "GND")
		(layer "F.Cu")
		(hatch edge 0.5)
		(priority 1)
		(connect_pads yes
			(clearance 0.5)
		)
		(min_thickness 0.25)
		(fill yes
			(thermal_gap 0.254)
			(thermal_bridge_width 0.508)
			(island_removal_mode 0)
		)
		(polygon
			(pts
				(xy 141.611205 86.59637) (xy 141.789325 86.71538) (xy 141.908335 86.8935) (xy 141.950135 87.1036)
				(xy 141.950135 88.1536) (xy 141.908335 88.36371) (xy 141.789325 88.54182) (xy 141.611205 88.66084)
				(xy 141.553235 88.67237) (xy 141.553235 88.7965) (xy 141.553235 88.79651) (xy 141.553085 88.79728)
				(xy 141.573275 89.00236) (xy 141.633325 89.20031) (xy 141.639715 89.21225) (xy 141.811205 89.24637)
				(xy 141.989325 89.36538) (xy 142.108335 89.5435) (xy 142.150135 89.7536) (xy 142.150135 90.2536)
				(xy 142.108335 90.4637) (xy 142.053235 90.54618) (xy 142.053235 90.58619) (xy 142.158335 90.7435)
				(xy 142.200135 90.9536) (xy 142.200135 91.4536) (xy 142.158335 91.6637) (xy 142.039325 91.84182)
				(xy 141.861205 91.96084) (xy 141.651105 92.00263) (xy 141.151105 92.00263) (xy 140.941005 91.96084)
				(xy 140.762885 91.84182) (xy 140.643865 91.6637) (xy 140.602075 91.4536) (xy 140.602075 90.9536)
				(xy 140.643865 90.7435) (xy 140.748975 90.58619) (xy 140.748975 90.54618) (xy 140.693865 90.4637)
				(xy 140.652075 90.2536) (xy 140.652075 90.10282) (xy 140.618155 90.06149) (xy 140.450795 89.74837)
				(xy 140.435095 89.69663) (xy 140.409605 89.64894) (xy 140.306545 89.3092) (xy 140.301245 89.25539)
				(xy 140.285545 89.20364) (xy 140.250755 88.85031) (xy 140.253425 88.82321) (xy 140.248105 88.7965)
				(xy 140.248975 88.79212) (xy 140.248975 88.67237) (xy 140.191005 88.66084) (xy 140.012885 88.54182)
				(xy 139.893875 88.36371) (xy 139.852075 88.1536) (xy 139.852075 87.1036) (xy 139.893875 86.8935)
				(xy 140.012885 86.71538) (xy 140.191005 86.59637) (xy 140.401105 86.55457) (xy 141.401105 86.55457)
			)
		)
	)
	(zone
		(layers "F.Cu" "B.Cu" "In1.Cu" "In2.Cu")
		(hatch edge 0.5)
		(connect_pads
			(clearance 0)
		)
		(min_thickness 0.25)
		(keepout
			(tracks not_allowed)
			(vias not_allowed)
			(pads not_allowed)
			(copperpour not_allowed)
			(footprints allowed)
		)
		(placement
			(enabled no)
			(sheetname "")
		)
		(fill
			(thermal_gap 0.5)
			(thermal_bridge_width 0.5)
			(island_removal_mode 0)
		)
		(polygon
			(pts
				(xy 198.940755 161.0886) (xy 198.941968 161.084868) (xy 198.945143 161.082561) (xy 198.949067 161.082561)
				(xy 198.952242 161.084868) (xy 198.953455 161.0886) (xy 198.937897 161.26654) (xy 198.891696 161.43908)
				(xy 198.816252 161.600984) (xy 198.713857 161.74734) (xy 198.587616 161.873704) (xy 198.441362 161.976244)
				(xy 198.279532 162.051846) (xy 198.107037 162.098217) (xy 197.929112 162.11395) (xy 197.925379 162.112741)
				(xy 197.923069 162.109568) (xy 197.923065 162.105644) (xy 197.925369 162.102466) (xy 197.9291 162.10125)
				(xy 198.01764 162.101168) (xy 198.192003 162.070266) (xy 198.358358 162.009574) (xy 198.511656 161.920933)
				(xy 198.647245 161.807034) (xy 198.761011 161.671333) (xy 198.849501 161.517948) (xy 198.910029 161.351534)
				(xy 198.94076 161.17714) (xy 198.940755 161.0886)
			)
		)
	)
	(zone
		(net "GND")
		(layer "B.Cu")
		(hatch edge 0.5)
		(connect_pads yes
			(clearance 0.5)
		)
		(min_thickness 0.25)
		(fill yes
			(thermal_gap 0.254)
			(thermal_bridge_width 0.508)
			(island_removal_mode 0)
		)
		(polygon
			(pts
				(xy 137.501085 84.00359) (xy 137.501085 122.56433) (xy 159.501115 122.56433) (xy 159.501115 84.00359)
				(xy 156.631105 84.00359)
			)
		)
	)
	(zone
		(net "+3V3")
		(layer "B.Cu")
		(hatch edge 0.5)
		(priority 8)
		(connect_pads yes
			(clearance 0.5)
		)
		(min_thickness 0.25)
		(fill yes
			(thermal_gap 0.254)
			(thermal_bridge_width 0.508)
			(island_removal_mode 0)
		)
		(polygon
			(pts
				(xy 141.101105 120.5036) (xy 139.760875 120.5036) (xy 139.760875 122.7036) (xy 139.401105 122.7036)
				(xy 139.401105 123.2036) (xy 141.101105 123.2036) (xy 141.101105 122.9036)
			)
		)
	)
	(zone
		(net "+3V3")
		(layer "B.Cu")
		(hatch edge 0.5)
		(priority 6)
		(connect_pads yes
			(clearance 0.5)
		)
		(min_thickness 0.25)
		(fill yes
			(thermal_gap 0.254)
			(thermal_bridge_width 0.508)
			(island_removal_mode 0)
		)
		(polygon
			(pts
				(xy 159.001105 120.82067) (xy 159.001105 122.4036) (xy 158.001105 122.4036) (xy 158.001105 122.9036)
				(xy 156.866785 122.9036) (xy 156.866785 120.82067)
			)
		)
	)
	(zone
		(net "GND")
		(layer "In1.Cu")
		(hatch edge 0.5)
		(priority 4)
		(connect_pads yes
			(clearance 0.5)
		)
		(min_thickness 0.25)
		(fill yes
			(thermal_gap 0.254)
			(thermal_bridge_width 0.508)
			(island_removal_mode 0)
		)
		(polygon
			(pts
				(xy 137.501085 84.08854) (xy 159.501115 84.08854) (xy 159.501115 123.00768) (xy 137.501095 123.00768)
			)
		)
	)
	(zone
		(net "+3V3")
		(layer "In2.Cu")
		(hatch edge 0.5)
		(priority 3)
		(connect_pads yes
			(clearance 0.5)
		)
		(min_thickness 0.25)
		(fill yes
			(thermal_gap 0.254)
			(thermal_bridge_width 0.508)
			(island_removal_mode 0)
		)
		(polygon
			(pts
				(xy 159.001105 88.2036) (xy 159.001105 122.6036) (xy 140.201105 122.6036) (xy 140.201105 100.1036)
				(xy 149.301105 100.1036) (xy 149.301105 88.2036)
			)
		)
	)
)
